(kicad_sch
	(version 20250114)
	(generator "eeschema")
	(generator_version "9.0")
	(paper "A3")
	(title_block
		(title "COM Express 7 Baseboard")
		(date "2025-02-04")
		(rev "1.1.2")
		(company "Antmicro Ltd")
		(comment 1 "www.antmicro.com")
	)
	(rectangle
		(start 154.94 92.71)
		(end 201.93 130.81)
		(stroke
			(width 0)
			(type dash)
		)
		(fill
			(type none)
		)
	)
	(text "Status LED"
		(exclude_from_sim no)
		(at 60.96 207.01 0)
		(effects
			(font
				(size 1.27 1.27)
			)
			(justify left bottom)
		)
	)
	(text "Front panel LEDs"
		(exclude_from_sim no)
		(at 59.69 158.75 0)
		(effects
			(font
				(size 2 2)
				(thickness 0.4)
				(bold yes)
			)
			(justify left bottom)
		)
	)
	(text "CPU FAN"
		(exclude_from_sim no)
		(at 354.33 200.66 0)
		(effects
			(font
				(size 1.27 1.27)
			)
			(justify left bottom)
		)
	)
	(text "Case fans can either share\nPWM speed control with CPU \nfan or be individually \ncontrolled from ADT7476AARQZ\n\n|PWM_{SRCSEL}| SOURCE  |\n|0      | ADT7476 |\n|1      | CPU_{PWM}   |\n\nIt's high by default"
		(exclude_from_sim no)
		(at 266.7 157.48 0)
		(effects
			(font
				(size 1.27 1.27)
			)
			(justify left bottom)
		)
	)
	(text "CASE FAN #1"
		(exclude_from_sim no)
		(at 355.6 93.98 0)
		(effects
			(font
				(size 1.27 1.27)
			)
			(justify left bottom)
		)
	)
	(text "Fan/Voltage/Temperature\nmonitor"
		(exclude_from_sim no)
		(at 100.076 26.162 0)
		(effects
			(font
				(size 2 2)
				(thickness 0.4)
				(bold yes)
			)
			(justify left bottom)
		)
	)
	(text "Cold side \ntemperature sensor"
		(exclude_from_sim no)
		(at 180.34 118.11 0)
		(effects
			(font
				(size 1.27 1.27)
			)
			(justify left bottom)
		)
	)
	(text "ADDR: 0x2D"
		(exclude_from_sim no)
		(at 113.03 119.38 0)
		(effects
			(font
				(size 1.27 1.27)
			)
			(justify left bottom)
		)
	)
	(text "Hot side \ntemperature sensor"
		(exclude_from_sim no)
		(at 180.34 99.06 0)
		(effects
			(font
				(size 1.27 1.27)
			)
			(justify left bottom)
		)
	)
	(text "Fan connector"
		(exclude_from_sim no)
		(at 307.34 20.32 0)
		(effects
			(font
				(size 2 2)
				(thickness 0.4)
				(bold yes)
			)
			(justify left bottom)
		)
	)
	(text "Power LED\nRED = Power connected\nGREEN = Boot and power OK"
		(exclude_from_sim no)
		(at 102.87 212.09 0)
		(effects
			(font
				(size 1.27 1.27)
			)
			(justify left bottom)
		)
	)
	(text "CASE FAN #2"
		(exclude_from_sim no)
		(at 354.33 149.86 0)
		(effects
			(font
				(size 1.27 1.27)
			)
			(justify left bottom)
		)
	)
	(junction
		(at 148.59 72.39)
		(diameter 0)
		(color 0 0 0 0)
	)
	(junction
		(at 335.28 106.68)
		(diameter 0)
		(color 0 0 0 0)
	)
	(junction
		(at 309.88 99.06)
		(diameter 0)
		(color 0 0 0 0)
	)
	(junction
		(at 161.29 119.38)
		(diameter 0)
		(color 0 0 0 0)
	)
	(junction
		(at 309.88 154.94)
		(diameter 0)
		(color 0 0 0 0)
	)
	(junction
		(at 265.43 210.82)
		(diameter 0)
		(color 0 0 0 0)
	)
	(junction
		(at 91.44 34.29)
		(diameter 0)
		(color 0 0 0 0)
	)
	(junction
		(at 64.77 43.18)
		(diameter 0)
		(color 0 0 0 0)
	)
	(junction
		(at 97.79 223.52)
		(diameter 0)
		(color 0 0 0 0)
	)
	(junction
		(at 344.17 138.43)
		(diameter 0)
		(color 0 0 0 0)
	)
	(junction
		(at 335.28 162.56)
		(diameter 0)
		(color 0 0 0 0)
	)
	(junction
		(at 309.88 205.74)
		(diameter 0)
		(color 0 0 0 0)
	)
	(junction
		(at 148.59 83.82)
		(diameter 0)
		(color 0 0 0 0)
	)
	(junction
		(at 271.78 165.1)
		(diameter 0)
		(color 0 0 0 0)
	)
	(junction
		(at 265.43 181.61)
		(diameter 0)
		(color 0 0 0 0)
	)
	(junction
		(at 335.28 146.05)
		(diameter 0)
		(color 0 0 0 0)
	)
	(junction
		(at 161.29 101.6)
		(diameter 0)
		(color 0 0 0 0)
	)
	(junction
		(at 83.82 34.29)
		(diameter 0)
		(color 0 0 0 0)
	)
	(junction
		(at 335.28 213.36)
		(diameter 0)
		(color 0 0 0 0)
	)
	(junction
		(at 307.34 90.17)
		(diameter 0)
		(color 0 0 0 0)
	)
	(junction
		(at 146.05 81.28)
		(diameter 0)
		(color 0 0 0 0)
	)
	(junction
		(at 271.78 109.22)
		(diameter 0)
		(color 0 0 0 0)
	)
	(junction
		(at 344.17 82.55)
		(diameter 0)
		(color 0 0 0 0)
	)
	(junction
		(at 335.28 90.17)
		(diameter 0)
		(color 0 0 0 0)
	)
	(junction
		(at 64.77 34.29)
		(diameter 0)
		(color 0 0 0 0)
	)
	(junction
		(at 335.28 196.85)
		(diameter 0)
		(color 0 0 0 0)
	)
	(junction
		(at 69.85 116.84)
		(diameter 0)
		(color 0 0 0 0)
	)
	(junction
		(at 157.48 88.9)
		(diameter 0)
		(color 0 0 0 0)
	)
	(junction
		(at 307.34 146.05)
		(diameter 0)
		(color 0 0 0 0)
	)
	(junction
		(at 91.44 50.8)
		(diameter 0)
		(color 0 0 0 0)
	)
	(junction
		(at 344.17 189.23)
		(diameter 0)
		(color 0 0 0 0)
	)
	(junction
		(at 307.34 196.85)
		(diameter 0)
		(color 0 0 0 0)
	)
	(junction
		(at 262.89 128.27)
		(diameter 0)
		(color 0 0 0 0)
	)
	(no_connect
		(at 93.98 207.01)
	)
	(bus_entry
		(at 71.12 91.44)
		(size -1.27 -1.27)
		(stroke
			(width 0)
			(type default)
		)
	)
	(bus_entry
		(at 71.12 88.9)
		(size -1.27 -1.27)
		(stroke
			(width 0)
			(type default)
		)
	)
	(wire
		(pts
			(xy 52.07 53.34) (xy 57.15 53.34)
		)
		(stroke
			(width 0)
			(type default)
		)
	)
	(wire
		(pts
			(xy 86.36 50.8) (xy 91.44 50.8)
		)
		(stroke
			(width 0)
			(type default)
		)
	)
	(wire
		(pts
			(xy 161.29 95.25) (xy 161.29 101.6)
		)
		(stroke
			(width 0)
			(type default)
		)
	)
	(wire
		(pts
			(xy 67.31 34.29) (xy 64.77 34.29)
		)
		(stroke
			(width 0)
			(type default)
		)
	)
	(wire
		(pts
			(xy 33.02 226.06) (xy 55.88 226.06)
		)
		(stroke
			(width 0)
			(type default)
		)
	)
	(wire
		(pts
			(xy 332.74 99.06) (xy 331.47 99.06)
		)
		(stroke
			(width 0)
			(type default)
		)
	)
	(wire
		(pts
			(xy 265.43 181.61) (xy 265.43 210.82)
		)
		(stroke
			(width 0)
			(type default)
		)
	)
	(wire
		(pts
			(xy 332.74 90.17) (xy 335.28 90.17)
		)
		(stroke
			(width 0)
			(type default)
		)
	)
	(bus
		(pts
			(xy 69.85 87.63) (xy 69.85 90.17)
		)
		(stroke
			(width 0)
			(type default)
		)
	)
	(wire
		(pts
			(xy 91.44 33.02) (xy 91.44 34.29)
		)
		(stroke
			(width 0)
			(type default)
		)
	)
	(wire
		(pts
			(xy 307.34 196.85) (xy 307.34 200.66)
		)
		(stroke
			(width 0)
			(type default)
		)
	)
	(wire
		(pts
			(xy 157.48 86.36) (xy 157.48 88.9)
		)
		(stroke
			(width 0)
			(type default)
		)
	)
	(wire
		(pts
			(xy 344.17 82.55) (xy 351.79 82.55)
		)
		(stroke
			(width 0)
			(type default)
		)
	)
	(wire
		(pts
			(xy 307.34 99.06) (xy 307.34 107.95)
		)
		(stroke
			(width 0)
			(type default)
		)
	)
	(wire
		(pts
			(xy 332.74 90.17) (xy 332.74 99.06)
		)
		(stroke
			(width 0)
			(type default)
		)
	)
	(wire
		(pts
			(xy 161.29 113.03) (xy 161.29 119.38)
		)
		(stroke
			(width 0)
			(type default)
		)
	)
	(wire
		(pts
			(xy 148.59 72.39) (xy 148.59 73.66)
		)
		(stroke
			(width 0)
			(type default)
		)
	)
	(wire
		(pts
			(xy 96.52 78.74) (xy 87.63 78.74)
		)
		(stroke
			(width 0)
			(type default)
		)
	)
	(wire
		(pts
			(xy 144.78 88.9) (xy 157.48 88.9)
		)
		(stroke
			(width 0)
			(type default)
		)
	)
	(wire
		(pts
			(xy 331.47 213.36) (xy 335.28 213.36)
		)
		(stroke
			(width 0)
			(type default)
		)
	)
	(wire
		(pts
			(xy 161.29 101.6) (xy 161.29 104.14)
		)
		(stroke
			(width 0)
			(type default)
		)
	)
	(wire
		(pts
			(xy 335.28 99.06) (xy 335.28 106.68)
		)
		(stroke
			(width 0)
			(type default)
		)
	)
	(wire
		(pts
			(xy 168.91 127) (xy 168.91 124.46)
		)
		(stroke
			(width 0)
			(type default)
		)
	)
	(wire
		(pts
			(xy 134.62 121.92) (xy 161.29 121.92)
		)
		(stroke
			(width 0)
			(type default)
		)
	)
	(wire
		(pts
			(xy 309.88 90.17) (xy 309.88 99.06)
		)
		(stroke
			(width 0)
			(type default)
		)
	)
	(wire
		(pts
			(xy 331.47 208.28) (xy 351.79 208.28)
		)
		(stroke
			(width 0)
			(type default)
		)
	)
	(wire
		(pts
			(xy 139.7 78.74) (xy 129.54 78.74)
		)
		(stroke
			(width 0)
			(type default)
		)
	)
	(wire
		(pts
			(xy 161.29 109.22) (xy 161.29 106.68)
		)
		(stroke
			(width 0)
			(type default)
		)
	)
	(wire
		(pts
			(xy 335.28 106.68) (xy 335.28 107.95)
		)
		(stroke
			(width 0)
			(type default)
		)
	)
	(wire
		(pts
			(xy 148.59 71.12) (xy 148.59 72.39)
		)
		(stroke
			(width 0)
			(type default)
		)
	)
	(wire
		(pts
			(xy 134.62 111.76) (xy 134.62 121.92)
		)
		(stroke
			(width 0)
			(type default)
		)
	)
	(wire
		(pts
			(xy 331.47 106.68) (xy 335.28 106.68)
		)
		(stroke
			(width 0)
			(type default)
		)
	)
	(wire
		(pts
			(xy 252.73 179.07) (xy 278.13 179.07)
		)
		(stroke
			(width 0)
			(type default)
		)
	)
	(wire
		(pts
			(xy 101.6 207.01) (xy 101.6 212.09)
		)
		(stroke
			(width 0)
			(type default)
		)
	)
	(wire
		(pts
			(xy 335.28 146.05) (xy 335.28 149.86)
		)
		(stroke
			(width 0)
			(type default)
		)
	)
	(wire
		(pts
			(xy 71.12 67.31) (xy 71.12 73.66)
		)
		(stroke
			(width 0)
			(type default)
		)
	)
	(wire
		(pts
			(xy 304.8 179.07) (xy 304.8 160.02)
		)
		(stroke
			(width 0)
			(type default)
		)
	)
	(wire
		(pts
			(xy 297.18 185.42) (xy 297.18 184.15)
		)
		(stroke
			(width 0)
			(type default)
		)
	)
	(wire
		(pts
			(xy 69.85 116.84) (xy 69.85 118.11)
		)
		(stroke
			(width 0)
			(type default)
		)
	)
	(wire
		(pts
			(xy 69.85 111.76) (xy 69.85 116.84)
		)
		(stroke
			(width 0)
			(type default)
		)
	)
	(wire
		(pts
			(xy 350.52 205.74) (xy 350.52 189.23)
		)
		(stroke
			(width 0)
			(type default)
		)
	)
	(wire
		(pts
			(xy 161.29 101.6) (xy 162.56 101.6)
		)
		(stroke
			(width 0)
			(type default)
		)
	)
	(wire
		(pts
			(xy 46.99 116.84) (xy 69.85 116.84)
		)
		(stroke
			(width 0)
			(type default)
		)
	)
	(wire
		(pts
			(xy 82.55 71.12) (xy 76.2 71.12)
		)
		(stroke
			(width 0)
			(type default)
		)
	)
	(wire
		(pts
			(xy 344.17 138.43) (xy 344.17 140.97)
		)
		(stroke
			(width 0)
			(type default)
		)
	)
	(wire
		(pts
			(xy 132.08 124.46) (xy 161.29 124.46)
		)
		(stroke
			(width 0)
			(type default)
		)
	)
	(wire
		(pts
			(xy 148.59 83.82) (xy 129.54 83.82)
		)
		(stroke
			(width 0)
			(type default)
		)
	)
	(wire
		(pts
			(xy 87.63 73.66) (xy 96.52 73.66)
		)
		(stroke
			(width 0)
			(type default)
		)
	)
	(wire
		(pts
			(xy 335.28 154.94) (xy 335.28 162.56)
		)
		(stroke
			(width 0)
			(type default)
		)
	)
	(wire
		(pts
			(xy 81.28 233.68) (xy 90.17 233.68)
		)
		(stroke
			(width 0)
			(type default)
		)
	)
	(wire
		(pts
			(xy 261.62 210.82) (xy 265.43 210.82)
		)
		(stroke
			(width 0)
			(type default)
		)
	)
	(wire
		(pts
			(xy 349.25 203.2) (xy 349.25 214.63)
		)
		(stroke
			(width 0)
			(type default)
		)
	)
	(wire
		(pts
			(xy 168.91 109.22) (xy 168.91 106.68)
		)
		(stroke
			(width 0)
			(type default)
		)
	)
	(wire
		(pts
			(xy 252.73 128.27) (xy 262.89 128.27)
		)
		(stroke
			(width 0)
			(type default)
		)
	)
	(wire
		(pts
			(xy 271.78 163.83) (xy 271.78 165.1)
		)
		(stroke
			(width 0)
			(type default)
		)
	)
	(wire
		(pts
			(xy 306.07 71.12) (xy 313.69 71.12)
		)
		(stroke
			(width 0)
			(type default)
		)
	)
	(wire
		(pts
			(xy 332.74 154.94) (xy 331.47 154.94)
		)
		(stroke
			(width 0)
			(type default)
		)
	)
	(wire
		(pts
			(xy 168.91 96.52) (xy 168.91 95.25)
		)
		(stroke
			(width 0)
			(type default)
		)
	)
	(wire
		(pts
			(xy 96.52 66.04) (xy 91.44 66.04)
		)
		(stroke
			(width 0)
			(type default)
		)
	)
	(wire
		(pts
			(xy 66.04 67.31) (xy 66.04 76.2)
		)
		(stroke
			(width 0)
			(type default)
		)
	)
	(wire
		(pts
			(xy 276.86 120.65) (xy 278.13 120.65)
		)
		(stroke
			(width 0)
			(type default)
		)
	)
	(wire
		(pts
			(xy 71.12 88.9) (xy 96.52 88.9)
		)
		(stroke
			(width 0)
			(type default)
		)
	)
	(polyline
		(pts
			(xy 233.68 12.7) (xy 233.68 284.48)
		)
		(stroke
			(width 0)
			(type dash)
		)
	)
	(wire
		(pts
			(xy 60.96 78.74) (xy 60.96 67.31)
		)
		(stroke
			(width 0)
			(type default)
		)
	)
	(wire
		(pts
			(xy 335.28 90.17) (xy 335.28 93.98)
		)
		(stroke
			(width 0)
			(type default)
		)
	)
	(wire
		(pts
			(xy 297.18 128.27) (xy 295.91 128.27)
		)
		(stroke
			(width 0)
			(type default)
		)
	)
	(wire
		(pts
			(xy 307.34 88.9) (xy 307.34 90.17)
		)
		(stroke
			(width 0)
			(type default)
		)
	)
	(wire
		(pts
			(xy 309.88 99.06) (xy 309.88 106.68)
		)
		(stroke
			(width 0)
			(type default)
		)
	)
	(wire
		(pts
			(xy 252.73 123.19) (xy 278.13 123.19)
		)
		(stroke
			(width 0)
			(type default)
		)
	)
	(wire
		(pts
			(xy 69.85 102.87) (xy 69.85 106.68)
		)
		(stroke
			(width 0)
			(type default)
		)
	)
	(wire
		(pts
			(xy 332.74 205.74) (xy 331.47 205.74)
		)
		(stroke
			(width 0)
			(type default)
		)
	)
	(wire
		(pts
			(xy 351.79 99.06) (xy 351.79 82.55)
		)
		(stroke
			(width 0)
			(type default)
		)
	)
	(wire
		(pts
			(xy 91.44 66.04) (xy 91.44 50.8)
		)
		(stroke
			(width 0)
			(type default)
		)
	)
	(wire
		(pts
			(xy 335.28 189.23) (xy 344.17 189.23)
		)
		(stroke
			(width 0)
			(type default)
		)
	)
	(wire
		(pts
			(xy 161.29 109.22) (xy 168.91 109.22)
		)
		(stroke
			(width 0)
			(type default)
		)
	)
	(wire
		(pts
			(xy 64.77 43.18) (xy 64.77 44.45)
		)
		(stroke
			(width 0)
			(type default)
		)
	)
	(wire
		(pts
			(xy 146.05 72.39) (xy 148.59 72.39)
		)
		(stroke
			(width 0)
			(type default)
		)
	)
	(wire
		(pts
			(xy 351.79 203.2) (xy 349.25 203.2)
		)
		(stroke
			(width 0)
			(type default)
		)
	)
	(wire
		(pts
			(xy 335.28 162.56) (xy 335.28 163.83)
		)
		(stroke
			(width 0)
			(type default)
		)
	)
	(wire
		(pts
			(xy 331.47 101.6) (xy 353.06 101.6)
		)
		(stroke
			(width 0)
			(type default)
		)
	)
	(wire
		(pts
			(xy 307.34 144.78) (xy 307.34 146.05)
		)
		(stroke
			(width 0)
			(type default)
		)
	)
	(wire
		(pts
			(xy 146.05 81.28) (xy 129.54 81.28)
		)
		(stroke
			(width 0)
			(type default)
		)
	)
	(wire
		(pts
			(xy 148.59 78.74) (xy 148.59 83.82)
		)
		(stroke
			(width 0)
			(type default)
		)
	)
	(wire
		(pts
			(xy 85.09 223.52) (xy 85.09 247.65)
		)
		(stroke
			(width 0)
			(type default)
		)
	)
	(wire
		(pts
			(xy 307.34 146.05) (xy 307.34 149.86)
		)
		(stroke
			(width 0)
			(type default)
		)
	)
	(wire
		(pts
			(xy 311.15 213.36) (xy 309.88 213.36)
		)
		(stroke
			(width 0)
			(type default)
		)
	)
	(wire
		(pts
			(xy 297.18 184.15) (xy 295.91 184.15)
		)
		(stroke
			(width 0)
			(type default)
		)
	)
	(wire
		(pts
			(xy 335.28 138.43) (xy 344.17 138.43)
		)
		(stroke
			(width 0)
			(type default)
		)
	)
	(wire
		(pts
			(xy 97.79 223.52) (xy 97.79 224.79)
		)
		(stroke
			(width 0)
			(type default)
		)
	)
	(wire
		(pts
			(xy 309.88 196.85) (xy 307.34 196.85)
		)
		(stroke
			(width 0)
			(type default)
		)
	)
	(wire
		(pts
			(xy 64.77 43.18) (xy 71.12 43.18)
		)
		(stroke
			(width 0)
			(type default)
		)
	)
	(wire
		(pts
			(xy 318.77 71.12) (xy 331.47 71.12)
		)
		(stroke
			(width 0)
			(type default)
		)
	)
	(wire
		(pts
			(xy 265.43 181.61) (xy 278.13 181.61)
		)
		(stroke
			(width 0)
			(type default)
		)
	)
	(polyline
		(pts
			(xy 12.7 144.78) (xy 233.68 144.78)
		)
		(stroke
			(width 0)
			(type dash)
		)
	)
	(wire
		(pts
			(xy 64.77 34.29) (xy 64.77 35.56)
		)
		(stroke
			(width 0)
			(type default)
		)
	)
	(wire
		(pts
			(xy 271.78 109.22) (xy 276.86 109.22)
		)
		(stroke
			(width 0)
			(type default)
		)
	)
	(wire
		(pts
			(xy 87.63 71.12) (xy 96.52 71.12)
		)
		(stroke
			(width 0)
			(type default)
		)
	)
	(wire
		(pts
			(xy 132.08 114.3) (xy 132.08 124.46)
		)
		(stroke
			(width 0)
			(type default)
		)
	)
	(wire
		(pts
			(xy 309.88 146.05) (xy 307.34 146.05)
		)
		(stroke
			(width 0)
			(type default)
		)
	)
	(wire
		(pts
			(xy 97.79 207.01) (xy 97.79 212.09)
		)
		(stroke
			(width 0)
			(type default)
		)
	)
	(wire
		(pts
			(xy 59.69 207.01) (xy 59.69 212.09)
		)
		(stroke
			(width 0)
			(type default)
		)
	)
	(wire
		(pts
			(xy 335.28 205.74) (xy 335.28 213.36)
		)
		(stroke
			(width 0)
			(type default)
		)
	)
	(wire
		(pts
			(xy 311.15 162.56) (xy 309.88 162.56)
		)
		(stroke
			(width 0)
			(type default)
		)
	)
	(wire
		(pts
			(xy 161.29 119.38) (xy 161.29 121.92)
		)
		(stroke
			(width 0)
			(type default)
		)
	)
	(wire
		(pts
			(xy 146.05 73.66) (xy 146.05 72.39)
		)
		(stroke
			(width 0)
			(type default)
		)
	)
	(wire
		(pts
			(xy 309.88 205.74) (xy 311.15 205.74)
		)
		(stroke
			(width 0)
			(type default)
		)
	)
	(wire
		(pts
			(xy 295.91 179.07) (xy 304.8 179.07)
		)
		(stroke
			(width 0)
			(type default)
		)
	)
	(polyline
		(pts
			(xy 154.94 111.76) (xy 201.93 111.76)
		)
		(stroke
			(width 0)
			(type dash)
		)
	)
	(wire
		(pts
			(xy 309.88 205.74) (xy 309.88 213.36)
		)
		(stroke
			(width 0)
			(type default)
		)
	)
	(wire
		(pts
			(xy 265.43 125.73) (xy 265.43 181.61)
		)
		(stroke
			(width 0)
			(type default)
		)
	)
	(wire
		(pts
			(xy 262.89 128.27) (xy 262.89 184.15)
		)
		(stroke
			(width 0)
			(type default)
		)
	)
	(wire
		(pts
			(xy 335.28 88.9) (xy 335.28 90.17)
		)
		(stroke
			(width 0)
			(type default)
		)
	)
	(wire
		(pts
			(xy 309.88 99.06) (xy 311.15 99.06)
		)
		(stroke
			(width 0)
			(type default)
		)
	)
	(wire
		(pts
			(xy 351.79 205.74) (xy 350.52 205.74)
		)
		(stroke
			(width 0)
			(type default)
		)
	)
	(wire
		(pts
			(xy 55.88 217.17) (xy 55.88 226.06)
		)
		(stroke
			(width 0)
			(type default)
		)
	)
	(wire
		(pts
			(xy 271.78 165.1) (xy 271.78 166.37)
		)
		(stroke
			(width 0)
			(type default)
		)
	)
	(wire
		(pts
			(xy 276.86 109.22) (xy 276.86 120.65)
		)
		(stroke
			(width 0)
			(type default)
		)
	)
	(wire
		(pts
			(xy 161.29 127) (xy 168.91 127)
		)
		(stroke
			(width 0)
			(type default)
		)
	)
	(wire
		(pts
			(xy 60.96 102.87) (xy 69.85 102.87)
		)
		(stroke
			(width 0)
			(type default)
		)
	)
	(wire
		(pts
			(xy 309.88 154.94) (xy 309.88 162.56)
		)
		(stroke
			(width 0)
			(type default)
		)
	)
	(bus
		(pts
			(xy 69.85 86.36) (xy 68.58 85.09)
		)
		(stroke
			(width 0)
			(type default)
		)
	)
	(wire
		(pts
			(xy 349.25 96.52) (xy 349.25 107.95)
		)
		(stroke
			(width 0)
			(type default)
		)
	)
	(wire
		(pts
			(xy 353.06 99.06) (xy 351.79 99.06)
		)
		(stroke
			(width 0)
			(type default)
		)
	)
	(polyline
		(pts
			(xy 132.08 144.78) (xy 132.08 284.48)
		)
		(stroke
			(width 0)
			(type dash)
		)
	)
	(wire
		(pts
			(xy 87.63 76.2) (xy 96.52 76.2)
		)
		(stroke
			(width 0)
			(type default)
		)
	)
	(wire
		(pts
			(xy 265.43 210.82) (xy 311.15 210.82)
		)
		(stroke
			(width 0)
			(type default)
		)
	)
	(wire
		(pts
			(xy 351.79 152.4) (xy 349.25 152.4)
		)
		(stroke
			(width 0)
			(type default)
		)
	)
	(wire
		(pts
			(xy 64.77 25.4) (xy 64.77 34.29)
		)
		(stroke
			(width 0)
			(type default)
		)
	)
	(wire
		(pts
			(xy 168.91 88.9) (xy 157.48 88.9)
		)
		(stroke
			(width 0)
			(type default)
		)
	)
	(wire
		(pts
			(xy 71.12 73.66) (xy 82.55 73.66)
		)
		(stroke
			(width 0)
			(type default)
		)
	)
	(wire
		(pts
			(xy 101.6 217.17) (xy 101.6 238.76)
		)
		(stroke
			(width 0)
			(type default)
		)
	)
	(wire
		(pts
			(xy 292.1 101.6) (xy 311.15 101.6)
		)
		(stroke
			(width 0)
			(type default)
		)
	)
	(wire
		(pts
			(xy 331.47 157.48) (xy 351.79 157.48)
		)
		(stroke
			(width 0)
			(type default)
		)
	)
	(wire
		(pts
			(xy 307.34 154.94) (xy 307.34 163.83)
		)
		(stroke
			(width 0)
			(type default)
		)
	)
	(wire
		(pts
			(xy 278.13 128.27) (xy 262.89 128.27)
		)
		(stroke
			(width 0)
			(type default)
		)
	)
	(wire
		(pts
			(xy 154.94 81.28) (xy 146.05 81.28)
		)
		(stroke
			(width 0)
			(type default)
		)
	)
	(wire
		(pts
			(xy 168.91 113.03) (xy 161.29 113.03)
		)
		(stroke
			(width 0)
			(type default)
		)
	)
	(wire
		(pts
			(xy 52.07 217.17) (xy 52.07 223.52)
		)
		(stroke
			(width 0)
			(type default)
		)
	)
	(wire
		(pts
			(xy 335.28 196.85) (xy 335.28 200.66)
		)
		(stroke
			(width 0)
			(type default)
		)
	)
	(wire
		(pts
			(xy 146.05 78.74) (xy 146.05 81.28)
		)
		(stroke
			(width 0)
			(type default)
		)
	)
	(wire
		(pts
			(xy 304.8 160.02) (xy 311.15 160.02)
		)
		(stroke
			(width 0)
			(type default)
		)
	)
	(wire
		(pts
			(xy 95.25 115.57) (xy 95.25 114.3)
		)
		(stroke
			(width 0)
			(type default)
		)
	)
	(wire
		(pts
			(xy 97.79 217.17) (xy 97.79 223.52)
		)
		(stroke
			(width 0)
			(type default)
		)
	)
	(wire
		(pts
			(xy 71.12 91.44) (xy 96.52 91.44)
		)
		(stroke
			(width 0)
			(type default)
		)
	)
	(wire
		(pts
			(xy 71.12 25.4) (xy 64.77 25.4)
		)
		(stroke
			(width 0)
			(type default)
		)
	)
	(wire
		(pts
			(xy 91.44 34.29) (xy 83.82 34.29)
		)
		(stroke
			(width 0)
			(type default)
		)
	)
	(wire
		(pts
			(xy 335.28 195.58) (xy 335.28 196.85)
		)
		(stroke
			(width 0)
			(type default)
		)
	)
	(wire
		(pts
			(xy 161.29 127) (xy 161.29 124.46)
		)
		(stroke
			(width 0)
			(type default)
		)
	)
	(wire
		(pts
			(xy 86.36 50.8) (xy 86.36 52.07)
		)
		(stroke
			(width 0)
			(type default)
		)
	)
	(wire
		(pts
			(xy 83.82 34.29) (xy 80.01 34.29)
		)
		(stroke
			(width 0)
			(type default)
		)
	)
	(wire
		(pts
			(xy 309.88 146.05) (xy 309.88 154.94)
		)
		(stroke
			(width 0)
			(type default)
		)
	)
	(wire
		(pts
			(xy 95.25 114.3) (xy 96.52 114.3)
		)
		(stroke
			(width 0)
			(type default)
		)
	)
	(bus
		(pts
			(xy 46.99 85.09) (xy 68.58 85.09)
		)
		(stroke
			(width 0)
			(type default)
		)
	)
	(wire
		(pts
			(xy 262.89 184.15) (xy 278.13 184.15)
		)
		(stroke
			(width 0)
			(type default)
		)
	)
	(wire
		(pts
			(xy 129.54 106.68) (xy 161.29 106.68)
		)
		(stroke
			(width 0)
			(type default)
		)
	)
	(wire
		(pts
			(xy 139.7 68.58) (xy 129.54 68.58)
		)
		(stroke
			(width 0)
			(type default)
		)
	)
	(wire
		(pts
			(xy 59.69 217.17) (xy 59.69 228.6)
		)
		(stroke
			(width 0)
			(type default)
		)
	)
	(wire
		(pts
			(xy 168.91 95.25) (xy 161.29 95.25)
		)
		(stroke
			(width 0)
			(type default)
		)
	)
	(wire
		(pts
			(xy 129.54 114.3) (xy 132.08 114.3)
		)
		(stroke
			(width 0)
			(type default)
		)
	)
	(wire
		(pts
			(xy 307.34 205.74) (xy 307.34 214.63)
		)
		(stroke
			(width 0)
			(type default)
		)
	)
	(wire
		(pts
			(xy 129.54 104.14) (xy 161.29 104.14)
		)
		(stroke
			(width 0)
			(type default)
		)
	)
	(wire
		(pts
			(xy 76.2 25.4) (xy 83.82 25.4)
		)
		(stroke
			(width 0)
			(type default)
		)
	)
	(wire
		(pts
			(xy 332.74 146.05) (xy 335.28 146.05)
		)
		(stroke
			(width 0)
			(type default)
		)
	)
	(wire
		(pts
			(xy 71.12 43.18) (xy 71.12 41.91)
		)
		(stroke
			(width 0)
			(type default)
		)
	)
	(wire
		(pts
			(xy 331.47 210.82) (xy 351.79 210.82)
		)
		(stroke
			(width 0)
			(type default)
		)
	)
	(wire
		(pts
			(xy 139.7 66.04) (xy 129.54 66.04)
		)
		(stroke
			(width 0)
			(type default)
		)
	)
	(wire
		(pts
			(xy 304.8 104.14) (xy 311.15 104.14)
		)
		(stroke
			(width 0)
			(type default)
		)
	)
	(wire
		(pts
			(xy 332.74 146.05) (xy 332.74 154.94)
		)
		(stroke
			(width 0)
			(type default)
		)
	)
	(wire
		(pts
			(xy 261.62 208.28) (xy 311.15 208.28)
		)
		(stroke
			(width 0)
			(type default)
		)
	)
	(wire
		(pts
			(xy 297.18 129.54) (xy 297.18 128.27)
		)
		(stroke
			(width 0)
			(type default)
		)
	)
	(wire
		(pts
			(xy 33.02 223.52) (xy 52.07 223.52)
		)
		(stroke
			(width 0)
			(type default)
		)
	)
	(wire
		(pts
			(xy 33.02 228.6) (xy 59.69 228.6)
		)
		(stroke
			(width 0)
			(type default)
		)
	)
	(wire
		(pts
			(xy 85.09 223.52) (xy 97.79 223.52)
		)
		(stroke
			(width 0)
			(type default)
		)
	)
	(wire
		(pts
			(xy 309.88 90.17) (xy 307.34 90.17)
		)
		(stroke
			(width 0)
			(type default)
		)
	)
	(wire
		(pts
			(xy 64.77 40.64) (xy 64.77 43.18)
		)
		(stroke
			(width 0)
			(type default)
		)
	)
	(wire
		(pts
			(xy 64.77 34.29) (xy 50.8 34.29)
		)
		(stroke
			(width 0)
			(type default)
		)
	)
	(wire
		(pts
			(xy 311.15 106.68) (xy 309.88 106.68)
		)
		(stroke
			(width 0)
			(type default)
		)
	)
	(wire
		(pts
			(xy 332.74 196.85) (xy 332.74 205.74)
		)
		(stroke
			(width 0)
			(type default)
		)
	)
	(wire
		(pts
			(xy 344.17 138.43) (xy 350.52 138.43)
		)
		(stroke
			(width 0)
			(type default)
		)
	)
	(wire
		(pts
			(xy 154.94 83.82) (xy 148.59 83.82)
		)
		(stroke
			(width 0)
			(type default)
		)
	)
	(wire
		(pts
			(xy 91.44 34.29) (xy 91.44 50.8)
		)
		(stroke
			(width 0)
			(type default)
		)
	)
	(wire
		(pts
			(xy 82.55 78.74) (xy 60.96 78.74)
		)
		(stroke
			(width 0)
			(type default)
		)
	)
	(wire
		(pts
			(xy 60.96 113.03) (xy 60.96 118.11)
		)
		(stroke
			(width 0)
			(type default)
		)
	)
	(wire
		(pts
			(xy 351.79 154.94) (xy 350.52 154.94)
		)
		(stroke
			(width 0)
			(type default)
		)
	)
	(wire
		(pts
			(xy 309.88 196.85) (xy 309.88 205.74)
		)
		(stroke
			(width 0)
			(type default)
		)
	)
	(wire
		(pts
			(xy 335.28 213.36) (xy 335.28 214.63)
		)
		(stroke
			(width 0)
			(type default)
		)
	)
	(wire
		(pts
			(xy 307.34 90.17) (xy 307.34 93.98)
		)
		(stroke
			(width 0)
			(type default)
		)
	)
	(wire
		(pts
			(xy 349.25 152.4) (xy 349.25 163.83)
		)
		(stroke
			(width 0)
			(type default)
		)
	)
	(wire
		(pts
			(xy 309.88 154.94) (xy 311.15 154.94)
		)
		(stroke
			(width 0)
			(type default)
		)
	)
	(wire
		(pts
			(xy 344.17 189.23) (xy 344.17 191.77)
		)
		(stroke
			(width 0)
			(type default)
		)
	)
	(wire
		(pts
			(xy 344.17 189.23) (xy 350.52 189.23)
		)
		(stroke
			(width 0)
			(type default)
		)
	)
	(wire
		(pts
			(xy 307.34 195.58) (xy 307.34 196.85)
		)
		(stroke
			(width 0)
			(type default)
		)
	)
	(wire
		(pts
			(xy 271.78 107.95) (xy 271.78 109.22)
		)
		(stroke
			(width 0)
			(type default)
		)
	)
	(wire
		(pts
			(xy 161.29 119.38) (xy 162.56 119.38)
		)
		(stroke
			(width 0)
			(type default)
		)
	)
	(wire
		(pts
			(xy 139.7 73.66) (xy 129.54 73.66)
		)
		(stroke
			(width 0)
			(type default)
		)
	)
	(wire
		(pts
			(xy 83.82 25.4) (xy 83.82 34.29)
		)
		(stroke
			(width 0)
			(type default)
		)
	)
	(wire
		(pts
			(xy 304.8 123.19) (xy 304.8 104.14)
		)
		(stroke
			(width 0)
			(type default)
		)
	)
	(wire
		(pts
			(xy 335.28 144.78) (xy 335.28 146.05)
		)
		(stroke
			(width 0)
			(type default)
		)
	)
	(wire
		(pts
			(xy 168.91 114.3) (xy 168.91 113.03)
		)
		(stroke
			(width 0)
			(type default)
		)
	)
	(wire
		(pts
			(xy 85.09 247.65) (xy 93.98 247.65)
		)
		(stroke
			(width 0)
			(type default)
		)
	)
	(wire
		(pts
			(xy 139.7 71.12) (xy 129.54 71.12)
		)
		(stroke
			(width 0)
			(type default)
		)
	)
	(bus
		(pts
			(xy 69.85 86.36) (xy 69.85 87.63)
		)
		(stroke
			(width 0)
			(type default)
		)
	)
	(wire
		(pts
			(xy 271.78 165.1) (xy 276.86 165.1)
		)
		(stroke
			(width 0)
			(type default)
		)
	)
	(wire
		(pts
			(xy 76.2 71.12) (xy 76.2 67.31)
		)
		(stroke
			(width 0)
			(type default)
		)
	)
	(wire
		(pts
			(xy 331.47 160.02) (xy 351.79 160.02)
		)
		(stroke
			(width 0)
			(type default)
		)
	)
	(wire
		(pts
			(xy 332.74 196.85) (xy 335.28 196.85)
		)
		(stroke
			(width 0)
			(type default)
		)
	)
	(wire
		(pts
			(xy 344.17 82.55) (xy 344.17 85.09)
		)
		(stroke
			(width 0)
			(type default)
		)
	)
	(wire
		(pts
			(xy 295.91 123.19) (xy 304.8 123.19)
		)
		(stroke
			(width 0)
			(type default)
		)
	)
	(wire
		(pts
			(xy 331.47 104.14) (xy 353.06 104.14)
		)
		(stroke
			(width 0)
			(type default)
		)
	)
	(wire
		(pts
			(xy 50.8 29.21) (xy 50.8 34.29)
		)
		(stroke
			(width 0)
			(type default)
		)
	)
	(wire
		(pts
			(xy 335.28 82.55) (xy 344.17 82.55)
		)
		(stroke
			(width 0)
			(type default)
		)
	)
	(wire
		(pts
			(xy 276.86 176.53) (xy 278.13 176.53)
		)
		(stroke
			(width 0)
			(type default)
		)
	)
	(wire
		(pts
			(xy 306.07 68.58) (xy 306.07 71.12)
		)
		(stroke
			(width 0)
			(type default)
		)
	)
	(wire
		(pts
			(xy 276.86 165.1) (xy 276.86 176.53)
		)
		(stroke
			(width 0)
			(type default)
		)
	)
	(wire
		(pts
			(xy 60.96 101.6) (xy 60.96 102.87)
		)
		(stroke
			(width 0)
			(type default)
		)
	)
	(wire
		(pts
			(xy 129.54 111.76) (xy 134.62 111.76)
		)
		(stroke
			(width 0)
			(type default)
		)
	)
	(wire
		(pts
			(xy 350.52 154.94) (xy 350.52 138.43)
		)
		(stroke
			(width 0)
			(type default)
		)
	)
	(wire
		(pts
			(xy 331.47 162.56) (xy 335.28 162.56)
		)
		(stroke
			(width 0)
			(type default)
		)
	)
	(wire
		(pts
			(xy 271.78 109.22) (xy 271.78 110.49)
		)
		(stroke
			(width 0)
			(type default)
		)
	)
	(wire
		(pts
			(xy 55.88 207.01) (xy 55.88 212.09)
		)
		(stroke
			(width 0)
			(type default)
		)
	)
	(wire
		(pts
			(xy 52.07 207.01) (xy 52.07 212.09)
		)
		(stroke
			(width 0)
			(type default)
		)
	)
	(wire
		(pts
			(xy 353.06 96.52) (xy 349.25 96.52)
		)
		(stroke
			(width 0)
			(type default)
		)
	)
	(wire
		(pts
			(xy 60.96 113.03) (xy 46.99 113.03)
		)
		(stroke
			(width 0)
			(type default)
		)
	)
	(wire
		(pts
			(xy 292.1 157.48) (xy 311.15 157.48)
		)
		(stroke
			(width 0)
			(type default)
		)
	)
	(wire
		(pts
			(xy 265.43 125.73) (xy 278.13 125.73)
		)
		(stroke
			(width 0)
			(type default)
		)
	)
	(wire
		(pts
			(xy 66.04 76.2) (xy 82.55 76.2)
		)
		(stroke
			(width 0)
			(type default)
		)
	)
	(wire
		(pts
			(xy 139.7 88.9) (xy 129.54 88.9)
		)
		(stroke
			(width 0)
			(type default)
		)
	)
	(label "~{PWR_OK}"
		(at 85.09 223.52 0)
		(effects
			(font
				(size 1.27 1.27)
			)
			(justify left bottom)
		)
	)
	(label "FAN_12V"
		(at 335.28 189.23 0)
		(effects
			(font
				(size 1.27 1.27)
			)
			(justify left bottom)
		)
	)
	(label "PWM_{A3V3}"
		(at 295.91 123.19 0)
		(effects
			(font
				(size 1.27 1.27)
			)
			(justify left bottom)
		)
	)
	(label "TACH_{B5V}"
		(at 339.09 157.48 0)
		(effects
			(font
				(size 1.27 1.27)
			)
			(justify left bottom)
		)
	)
	(label "PWM2"
		(at 252.73 179.07 0)
		(effects
			(font
				(size 1.27 1.27)
			)
			(justify left bottom)
		)
	)
	(label "SMBus.SDA"
		(at 72.39 88.9 0)
		(effects
			(font
				(size 1.27 1.27)
			)
			(justify left bottom)
		)
	)
	(label "TACH_{B3V3}"
		(at 139.7 71.12 180)
		(effects
			(font
				(size 1.27 1.27)
			)
			(justify right bottom)
		)
	)
	(label "PWM1"
		(at 154.94 83.82 180)
		(effects
			(font
				(size 1.27 1.27)
			)
			(justify right bottom)
		)
	)
	(label "FAN_12V"
		(at 335.28 138.43 0)
		(effects
			(font
				(size 1.27 1.27)
			)
			(justify left bottom)
		)
	)
	(label "PWM1"
		(at 252.73 123.19 0)
		(effects
			(font
				(size 1.27 1.27)
			)
			(justify left bottom)
		)
	)
	(label "PWM2"
		(at 154.94 81.28 180)
		(effects
			(font
				(size 1.27 1.27)
			)
			(justify right bottom)
		)
	)
	(label "~{ADDREN}"
		(at 46.99 113.03 0)
		(effects
			(font
				(size 1.27 1.27)
			)
			(justify left bottom)
		)
	)
	(label "PWM_{B5V}"
		(at 339.09 160.02 0)
		(effects
			(font
				(size 1.27 1.27)
			)
			(justify left bottom)
		)
	)
	(label "TACH_{B3V3}"
		(at 292.1 157.48 0)
		(effects
			(font
				(size 1.27 1.27)
			)
			(justify left bottom)
		)
	)
	(label "PWM_{A5V}"
		(at 339.09 104.14 0)
		(effects
			(font
				(size 1.27 1.27)
			)
			(justify left bottom)
		)
	)
	(label "~{ADDREN}"
		(at 139.7 78.74 180)
		(effects
			(font
				(size 1.27 1.27)
			)
			(justify right bottom)
		)
	)
	(label "PWM_{C5V}"
		(at 339.09 210.82 0)
		(effects
			(font
				(size 1.27 1.27)
			)
			(justify left bottom)
		)
	)
	(label "PWM_{B3V3}"
		(at 295.91 179.07 0)
		(effects
			(font
				(size 1.27 1.27)
			)
			(justify left bottom)
		)
	)
	(label "~{ADDRSEL}"
		(at 46.99 116.84 0)
		(effects
			(font
				(size 1.27 1.27)
			)
			(justify left bottom)
		)
	)
	(label "PWM_{SRCSEL}"
		(at 252.73 128.27 0)
		(effects
			(font
				(size 1.27 1.27)
			)
			(justify left bottom)
		)
	)
	(label "TACH_{C5V}"
		(at 339.09 208.28 0)
		(effects
			(font
				(size 1.27 1.27)
			)
			(justify left bottom)
		)
	)
	(label "TACH_{A3V3}"
		(at 292.1 101.6 0)
		(effects
			(font
				(size 1.27 1.27)
			)
			(justify left bottom)
		)
	)
	(label "TACH_{A5V}"
		(at 339.09 101.6 0)
		(effects
			(font
				(size 1.27 1.27)
			)
			(justify left bottom)
		)
	)
	(label "FAN_12V"
		(at 331.47 71.12 180)
		(effects
			(font
				(size 1.27 1.27)
			)
			(justify right bottom)
		)
	)
	(label "PWM_{SRCSEL}"
		(at 168.91 88.9 180)
		(effects
			(font
				(size 1.27 1.27)
			)
			(justify right bottom)
		)
	)
	(label "TACH_{A3V3}"
		(at 139.7 73.66 180)
		(effects
			(font
				(size 1.27 1.27)
			)
			(justify right bottom)
		)
	)
	(label "FAN_12V"
		(at 335.28 82.55 0)
		(effects
			(font
				(size 1.27 1.27)
			)
			(justify left bottom)
		)
	)
	(label "~{ADDRSEL}"
		(at 139.7 66.04 180)
		(effects
			(font
				(size 1.27 1.27)
			)
			(justify right bottom)
		)
	)
	(label "SMBus.SCL"
		(at 72.39 91.44 0)
		(effects
			(font
				(size 1.27 1.27)
			)
			(justify left bottom)
		)
	)
	(hierarchical_label "LED_G"
		(shape input)
		(at 33.02 226.06 180)
		(effects
			(font
				(size 1.27 1.27)
			)
			(justify right)
		)
	)
	(hierarchical_label "LED_R"
		(shape input)
		(at 33.02 228.6 180)
		(effects
			(font
				(size 1.27 1.27)
			)
			(justify right)
		)
	)
	(hierarchical_label "PWR_OK"
		(shape input)
		(at 81.28 233.68 180)
		(effects
			(font
				(size 1.27 1.27)
			)
			(justify right)
		)
	)
	(hierarchical_label "SMBus{I2C}"
		(shape input)
		(at 46.99 85.09 180)
		(effects
			(font
				(size 1.27 1.27)
			)
			(justify right)
		)
	)
	(hierarchical_label "~{RESET}"
		(shape input)
		(at 52.07 53.34 180)
		(effects
			(font
				(size 1.27 1.27)
			)
			(justify right)
		)
	)
	(hierarchical_label "LED_B"
		(shape input)
		(at 33.02 223.52 180)
		(effects
			(font
				(size 1.27 1.27)
			)
			(justify right)
		)
	)
	(hierarchical_label "TACH_{CPUFAN}"
		(shape output)
		(at 261.62 208.28 180)
		(effects
			(font
				(size 1.27 1.27)
			)
			(justify right)
		)
	)
	(hierarchical_label "PWM_{CPUFAN}"
		(shape input)
		(at 261.62 210.82 180)
		(effects
			(font
				(size 1.27 1.27)
			)
			(justify right)
		)
	)
	(symbol
		(lib_id "antmicroCapacitors0402:C_100n_0402")
		(at 335.28 205.74 90)
		(unit 1)
		(exclude_from_sim no)
		(in_bom yes)
		(on_board yes)
		(dnp no)
		(fields_autoplaced yes)
		(property "Reference" "C92"
			(at 337.82 201.9236 90)
			(effects
				(font
					(size 1.27 1.27)
					(thickness 0.15)
				)
				(justify right)
			)
		)
		(property "Value" "C_100n_0402"
			(at 345.44 185.42 0)
			(effects
				(font
					(size 1.27 1.27)
					(thickness 0.15)
				)
				(justify left bottom)
				(hide yes)
			)
		)
		(property "Footprint" "antmicro-footprints:C_0402_1005Metric"
			(at 347.98 185.42 0)
			(effects
				(font
					(size 1.27 1.27)
					(thickness 0.15)
				)
				(justify left bottom)
				(hide yes)
			)
		)
		(property "Datasheet" "https://www.murata.com/products/productdetail?partno=GRM155R61H104KE14%23"
			(at 350.52 185.42 0)
			(effects
				(font
					(size 1.27 1.27)
					(thickness 0.15)
				)
				(justify left bottom)
				(hide yes)
			)
		)
		(property "Description" ""
			(at 335.28 205.74 0)
			(effects
				(font
					(size 1.27 1.27)
				)
				(hide yes)
			)
		)
		(property "MPN" "GRM155R61H104KE14D"
			(at 353.06 185.42 0)
			(effects
				(font
					(size 1.27 1.27)
					(thickness 0.15)
				)
				(justify left bottom)
				(hide yes)
			)
		)
		(property "Manufacturer" "Murata"
			(at 355.6 185.42 0)
			(effects
				(font
					(size 1.27 1.27)
					(thickness 0.15)
				)
				(justify left bottom)
				(hide yes)
			)
		)
		(property "License" "Apache-2.0"
			(at 358.14 185.42 0)
			(effects
				(font
					(size 1.27 1.27)
					(thickness 0.15)
				)
				(justify left bottom)
				(hide yes)
			)
		)
		(property "Author" "Antmicro"
			(at 360.68 185.42 0)
			(effects
				(font
					(size 1.27 1.27)
					(thickness 0.15)
				)
				(justify left bottom)
				(hide yes)
			)
		)
		(property "Val" "100n"
			(at 337.82 204.4636 90)
			(effects
				(font
					(size 1.27 1.27)
					(thickness 0.15)
				)
				(justify right)
			)
		)
		(property "Voltage" "50V"
			(at 363.22 185.42 0)
			(effects
				(font
					(size 1.27 1.27)
				)
				(justify left bottom)
				(hide yes)
			)
		)
		(property "Dielectric" "X5R"
			(at 365.76 185.42 0)
			(effects
				(font
					(size 1.27 1.27)
				)
				(justify left bottom)
				(hide yes)
			)
		)
		(property "Public" "False"
			(at 368.3 185.42 0)
			(effects
				(font
					(size 1.27 1.27)
				)
				(justify left bottom)
				(hide yes)
			)
		)
		(pin "2"
		)
		(pin "1"
		)
		(instances
			(project "com-express-7-baseboard"
				(path ""
					(reference "C92")
					(unit 1)
				)
			)
		)
	)
	(symbol
		(lib_id "antmicropower:GND")
		(at 297.18 185.42 0)
		(mirror y)
		(unit 1)
		(exclude_from_sim no)
		(in_bom yes)
		(on_board yes)
		(dnp no)
		(property "Reference" "#PWR0205"
			(at 288.29 187.96 0)
			(effects
				(font
					(size 1.27 1.27)
					(thickness 0.15)
				)
				(justify left bottom)
				(hide yes)
			)
		)
		(property "Value" "GND"
			(at 297.18 189.23 0)
			(effects
				(font
					(size 1.27 1.27)
					(thickness 0.15)
				)
			)
		)
		(property "Footprint" ""
			(at 288.29 193.04 0)
			(effects
				(font
					(size 1.27 1.27)
					(thickness 0.15)
				)
				(justify left bottom)
				(hide yes)
			)
		)
		(property "Datasheet" ""
			(at 288.29 198.12 0)
			(effects
				(font
					(size 1.27 1.27)
					(thickness 0.15)
				)
				(justify left bottom)
				(hide yes)
			)
		)
		(property "Description" ""
			(at 297.18 185.42 0)
			(effects
				(font
					(size 1.27 1.27)
				)
				(hide yes)
			)
		)
		(property "Author" "Antmicro"
			(at 288.29 193.04 0)
			(effects
				(font
					(size 1.27 1.27)
					(thickness 0.15)
				)
				(justify left bottom)
				(hide yes)
			)
		)
		(property "License" "Apache-2.0"
			(at 288.29 195.58 0)
			(effects
				(font
					(size 1.27 1.27)
					(thickness 0.15)
				)
				(justify left bottom)
				(hide yes)
			)
		)
		(pin "1"
		)
		(instances
			(project "com-express-7-baseboard"
				(path ""
					(reference "#PWR0205")
					(unit 1)
				)
			)
		)
	)
	(symbol
		(lib_id "antmicroCapacitors0402:C_100n_0402")
		(at 335.28 99.06 90)
		(unit 1)
		(exclude_from_sim no)
		(in_bom yes)
		(on_board yes)
		(dnp no)
		(fields_autoplaced yes)
		(property "Reference" "C90"
			(at 337.82 95.2436 90)
			(effects
				(font
					(size 1.27 1.27)
					(thickness 0.15)
				)
				(justify right)
			)
		)
		(property "Value" "C_100n_0402"
			(at 345.44 78.74 0)
			(effects
				(font
					(size 1.27 1.27)
					(thickness 0.15)
				)
				(justify left bottom)
				(hide yes)
			)
		)
		(property "Footprint" "antmicro-footprints:C_0402_1005Metric"
			(at 347.98 78.74 0)
			(effects
				(font
					(size 1.27 1.27)
					(thickness 0.15)
				)
				(justify left bottom)
				(hide yes)
			)
		)
		(property "Datasheet" "https://www.murata.com/products/productdetail?partno=GRM155R61H104KE14%23"
			(at 350.52 78.74 0)
			(effects
				(font
					(size 1.27 1.27)
					(thickness 0.15)
				)
				(justify left bottom)
				(hide yes)
			)
		)
		(property "Description" ""
			(at 335.28 99.06 0)
			(effects
				(font
					(size 1.27 1.27)
				)
				(hide yes)
			)
		)
		(property "MPN" "GRM155R61H104KE14D"
			(at 353.06 78.74 0)
			(effects
				(font
					(size 1.27 1.27)
					(thickness 0.15)
				)
				(justify left bottom)
				(hide yes)
			)
		)
		(property "Manufacturer" "Murata"
			(at 355.6 78.74 0)
			(effects
				(font
					(size 1.27 1.27)
					(thickness 0.15)
				)
				(justify left bottom)
				(hide yes)
			)
		)
		(property "License" "Apache-2.0"
			(at 358.14 78.74 0)
			(effects
				(font
					(size 1.27 1.27)
					(thickness 0.15)
				)
				(justify left bottom)
				(hide yes)
			)
		)
		(property "Author" "Antmicro"
			(at 360.68 78.74 0)
			(effects
				(font
					(size 1.27 1.27)
					(thickness 0.15)
				)
				(justify left bottom)
				(hide yes)
			)
		)
		(property "Val" "100n"
			(at 337.82 97.7836 90)
			(effects
				(font
					(size 1.27 1.27)
					(thickness 0.15)
				)
				(justify right)
			)
		)
		(property "Voltage" "50V"
			(at 363.22 78.74 0)
			(effects
				(font
					(size 1.27 1.27)
				)
				(justify left bottom)
				(hide yes)
			)
		)
		(property "Dielectric" "X5R"
			(at 365.76 78.74 0)
			(effects
				(font
					(size 1.27 1.27)
				)
				(justify left bottom)
				(hide yes)
			)
		)
		(property "Public" "False"
			(at 368.3 78.74 0)
			(effects
				(font
					(size 1.27 1.27)
				)
				(justify left bottom)
				(hide yes)
			)
		)
		(pin "2"
		)
		(pin "1"
		)
		(instances
			(project "com-express-7-baseboard"
				(path ""
					(reference "C90")
					(unit 1)
				)
			)
		)
	)
	(symbol
		(lib_id "antmicropower:GND")
		(at 344.17 146.05 0)
		(unit 1)
		(exclude_from_sim no)
		(in_bom yes)
		(on_board yes)
		(dnp no)
		(property "Reference" "#PWR0262"
			(at 353.06 148.59 0)
			(effects
				(font
					(size 1.27 1.27)
					(thickness 0.15)
				)
				(justify left bottom)
				(hide yes)
			)
		)
		(property "Value" "GND"
			(at 344.17 149.86 0)
			(effects
				(font
					(size 1.27 1.27)
					(thickness 0.15)
				)
			)
		)
		(property "Footprint" ""
			(at 353.06 153.67 0)
			(effects
				(font
					(size 1.27 1.27)
					(thickness 0.15)
				)
				(justify left bottom)
				(hide yes)
			)
		)
		(property "Datasheet" ""
			(at 353.06 158.75 0)
			(effects
				(font
					(size 1.27 1.27)
					(thickness 0.15)
				)
				(justify left bottom)
				(hide yes)
			)
		)
		(property "Description" ""
			(at 344.17 146.05 0)
			(effects
				(font
					(size 1.27 1.27)
				)
				(hide yes)
			)
		)
		(property "Author" "Antmicro"
			(at 353.06 153.67 0)
			(effects
				(font
					(size 1.27 1.27)
					(thickness 0.15)
				)
				(justify left bottom)
				(hide yes)
			)
		)
		(property "License" "Apache-2.0"
			(at 353.06 156.21 0)
			(effects
				(font
					(size 1.27 1.27)
					(thickness 0.15)
				)
				(justify left bottom)
				(hide yes)
			)
		)
		(pin "1"
		)
		(instances
			(project "com-express-7-baseboard"
				(path ""
					(reference "#PWR0262")
					(unit 1)
				)
			)
		)
	)
	(symbol
		(lib_id "antmicropower:+3V3")
		(at 271.78 163.83 0)
		(unit 1)
		(exclude_from_sim no)
		(in_bom yes)
		(on_board yes)
		(dnp no)
		(property "Reference" "#PWR0202"
			(at 287.02 163.83 0)
			(effects
				(font
					(size 1.27 1.27)
					(thickness 0.15)
				)
				(justify left bottom)
				(hide yes)
			)
		)
		(property "Value" "+3V3"
			(at 271.78 160.02 0)
			(effects
				(font
					(size 1.27 1.27)
					(thickness 0.15)
				)
			)
		)
		(property "Footprint" ""
			(at 287.02 171.45 0)
			(effects
				(font
					(size 1.27 1.27)
					(thickness 0.15)
				)
				(justify left bottom)
				(hide yes)
			)
		)
		(property "Datasheet" ""
			(at 287.02 173.99 0)
			(effects
				(font
					(size 1.27 1.27)
					(thickness 0.15)
				)
				(justify left bottom)
				(hide yes)
			)
		)
		(property "Description" ""
			(at 271.78 163.83 0)
			(effects
				(font
					(size 1.27 1.27)
				)
				(hide yes)
			)
		)
		(property "Author" "Antmicro"
			(at 287.02 166.37 0)
			(effects
				(font
					(size 1.27 1.27)
					(thickness 0.15)
				)
				(justify left bottom)
				(hide yes)
			)
		)
		(property "License" "Apache-2.0"
			(at 287.02 168.91 0)
			(effects
				(font
					(size 1.27 1.27)
					(thickness 0.15)
				)
				(justify left bottom)
				(hide yes)
			)
		)
		(pin "1"
		)
		(instances
			(project "com-express-7-baseboard"
				(path ""
					(reference "#PWR0202")
					(unit 1)
				)
			)
		)
	)
	(symbol
		(lib_id "antmicropower:+5V")
		(at 335.28 144.78 0)
		(unit 1)
		(exclude_from_sim no)
		(in_bom yes)
		(on_board yes)
		(dnp no)
		(property "Reference" "#PWR0216"
			(at 350.52 147.32 0)
			(effects
				(font
					(size 1.27 1.27)
					(thickness 0.15)
				)
				(justify left bottom)
				(hide yes)
			)
		)
		(property "Value" "+5V"
			(at 335.28 140.97 0)
			(effects
				(font
					(size 1.27 1.27)
					(thickness 0.15)
				)
			)
		)
		(property "Footprint" ""
			(at 350.52 152.4 0)
			(effects
				(font
					(size 1.27 1.27)
					(thickness 0.15)
				)
				(justify left bottom)
				(hide yes)
			)
		)
		(property "Datasheet" ""
			(at 350.52 154.94 0)
			(effects
				(font
					(size 1.27 1.27)
					(thickness 0.15)
				)
				(justify left bottom)
				(hide yes)
			)
		)
		(property "Description" ""
			(at 335.28 144.78 0)
			(effects
				(font
					(size 1.27 1.27)
				)
				(hide yes)
			)
		)
		(property "Author" "Antmicro"
			(at 350.52 152.4 0)
			(effects
				(font
					(size 1.27 1.27)
					(thickness 0.15)
				)
				(justify left bottom)
				(hide yes)
			)
		)
		(property "License" "Apache-2.0"
			(at 350.52 154.94 0)
			(effects
				(font
					(size 1.27 1.27)
					(thickness 0.15)
				)
				(justify left bottom)
				(hide yes)
			)
		)
		(pin "1"
		)
		(instances
			(project "com-express-7-baseboard"
				(path ""
					(reference "#PWR0216")
					(unit 1)
				)
			)
		)
	)
	(symbol
		(lib_id "antmicropower:+3V3")
		(at 307.34 195.58 0)
		(unit 1)
		(exclude_from_sim no)
		(in_bom yes)
		(on_board yes)
		(dnp no)
		(property "Reference" "#PWR0211"
			(at 322.58 195.58 0)
			(effects
				(font
					(size 1.27 1.27)
					(thickness 0.15)
				)
				(justify left bottom)
				(hide yes)
			)
		)
		(property "Value" "+3V3"
			(at 307.34 191.77 0)
			(effects
				(font
					(size 1.27 1.27)
					(thickness 0.15)
				)
			)
		)
		(property "Footprint" ""
			(at 322.58 203.2 0)
			(effects
				(font
					(size 1.27 1.27)
					(thickness 0.15)
				)
				(justify left bottom)
				(hide yes)
			)
		)
		(property "Datasheet" ""
			(at 322.58 205.74 0)
			(effects
				(font
					(size 1.27 1.27)
					(thickness 0.15)
				)
				(justify left bottom)
				(hide yes)
			)
		)
		(property "Description" ""
			(at 307.34 195.58 0)
			(effects
				(font
					(size 1.27 1.27)
				)
				(hide yes)
			)
		)
		(property "Author" "Antmicro"
			(at 322.58 198.12 0)
			(effects
				(font
					(size 1.27 1.27)
					(thickness 0.15)
				)
				(justify left bottom)
				(hide yes)
			)
		)
		(property "License" "Apache-2.0"
			(at 322.58 200.66 0)
			(effects
				(font
					(size 1.27 1.27)
					(thickness 0.15)
				)
				(justify left bottom)
				(hide yes)
			)
		)
		(pin "1"
		)
		(instances
			(project "com-express-7-baseboard"
				(path ""
					(reference "#PWR0211")
					(unit 1)
				)
			)
		)
	)
	(symbol
		(lib_id "antmicroResistors0402:R_100k_0402")
		(at 64.77 40.64 90)
		(unit 1)
		(exclude_from_sim no)
		(in_bom yes)
		(on_board yes)
		(dnp no)
		(fields_autoplaced yes)
		(property "Reference" "R144"
			(at 62.23 36.8299 90)
			(effects
				(font
					(size 1.27 1.27)
					(thickness 0.15)
				)
				(justify left)
			)
		)
		(property "Value" "R_100k_0402"
			(at 77.47 20.32 0)
			(effects
				(font
					(size 1.27 1.27)
					(thickness 0.15)
				)
				(justify left bottom)
				(hide yes)
			)
		)
		(property "Footprint" "antmicro-footprints:R_0402_1005Metric"
			(at 80.01 20.32 0)
			(effects
				(font
					(size 1.27 1.27)
					(thickness 0.15)
				)
				(justify left bottom)
				(hide yes)
			)
		)
		(property "Datasheet" "https://www.bourns.com/docs/product-datasheets/cr.pdf"
			(at 82.55 20.32 0)
			(effects
				(font
					(size 1.27 1.27)
					(thickness 0.15)
				)
				(justify left bottom)
				(hide yes)
			)
		)
		(property "Description" ""
			(at 64.77 40.64 0)
			(effects
				(font
					(size 1.27 1.27)
				)
				(hide yes)
			)
		)
		(property "MPN" "CR0402-FX-1003GLF"
			(at 85.09 20.32 0)
			(effects
				(font
					(size 1.27 1.27)
					(thickness 0.15)
				)
				(justify left bottom)
				(hide yes)
			)
		)
		(property "Manufacturer" "Bourns"
			(at 87.63 20.32 0)
			(effects
				(font
					(size 1.27 1.27)
					(thickness 0.15)
				)
				(justify left bottom)
				(hide yes)
			)
		)
		(property "License" "Apache-2.0"
			(at 90.17 20.32 0)
			(effects
				(font
					(size 1.27 1.27)
					(thickness 0.15)
				)
				(justify left bottom)
				(hide yes)
			)
		)
		(property "Author" "Antmicro"
			(at 92.71 20.32 0)
			(effects
				(font
					(size 1.27 1.27)
					(thickness 0.15)
				)
				(justify left bottom)
				(hide yes)
			)
		)
		(property "Val" "100k"
			(at 62.23 39.3699 90)
			(effects
				(font
					(size 1.27 1.27)
					(thickness 0.15)
				)
				(justify left)
			)
		)
		(property "Tolerance" "1%"
			(at 74.93 20.32 0)
			(effects
				(font
					(size 1.27 1.27)
				)
				(justify left bottom)
				(hide yes)
			)
		)
		(property "Public" "False"
			(at 95.25 20.32 0)
			(effects
				(font
					(size 1.27 1.27)
				)
				(justify left bottom)
				(hide yes)
			)
		)
		(pin "2"
		)
		(pin "1"
		)
		(instances
			(project "com-express-7-baseboard"
				(path ""
					(reference "R144")
					(unit 1)
				)
			)
		)
	)
	(symbol
		(lib_id "antmicroResistors0402:R_0R_0402")
		(at 60.96 123.19 90)
		(unit 1)
		(exclude_from_sim no)
		(in_bom yes)
		(on_board yes)
		(dnp no)
		(fields_autoplaced yes)
		(property "Reference" "R143"
			(at 63.5 119.3799 90)
			(effects
				(font
					(size 1.27 1.27)
					(thickness 0.15)
				)
				(justify right)
			)
		)
		(property "Value" "R_0R_0402"
			(at 73.66 102.87 0)
			(effects
				(font
					(size 1.27 1.27)
					(thickness 0.15)
				)
				(justify left bottom)
				(hide yes)
			)
		)
		(property "Footprint" "antmicro-footprints:R_0402_1005Metric"
			(at 76.2 102.87 0)
			(effects
				(font
					(size 1.27 1.27)
					(thickness 0.15)
				)
				(justify left bottom)
				(hide yes)
			)
		)
		(property "Datasheet" "https://industrial.panasonic.com/cdbs/www-data/pdf/RDA0000/AOA0000C301.pdf"
			(at 78.74 102.87 0)
			(effects
				(font
					(size 1.27 1.27)
					(thickness 0.15)
				)
				(justify left bottom)
				(hide yes)
			)
		)
		(property "Description" ""
			(at 60.96 123.19 0)
			(effects
				(font
					(size 1.27 1.27)
				)
				(hide yes)
			)
		)
		(property "MPN" "ERJ2GE0R00X"
			(at 81.28 102.87 0)
			(effects
				(font
					(size 1.27 1.27)
					(thickness 0.15)
				)
				(justify left bottom)
				(hide yes)
			)
		)
		(property "Manufacturer" "Panasonic"
			(at 83.82 102.87 0)
			(effects
				(font
					(size 1.27 1.27)
					(thickness 0.15)
				)
				(justify left bottom)
				(hide yes)
			)
		)
		(property "License" "Apache-2.0"
			(at 86.36 102.87 0)
			(effects
				(font
					(size 1.27 1.27)
					(thickness 0.15)
				)
				(justify left bottom)
				(hide yes)
			)
		)
		(property "Author" "Antmicro"
			(at 88.9 102.87 0)
			(effects
				(font
					(size 1.27 1.27)
					(thickness 0.15)
				)
				(justify left bottom)
				(hide yes)
			)
		)
		(property "Val" "0R"
			(at 63.5 121.9199 90)
			(effects
				(font
					(size 1.27 1.27)
					(thickness 0.15)
				)
				(justify right)
			)
		)
		(property "Tolerance" "~"
			(at 71.12 102.87 0)
			(effects
				(font
					(size 1.27 1.27)
				)
				(justify left bottom)
				(hide yes)
			)
		)
		(property "Current" "1A"
			(at 91.44 102.87 0)
			(effects
				(font
					(size 1.27 1.27)
					(thickness 0.15)
				)
				(justify left bottom)
				(hide yes)
			)
		)
		(property "Public" "False"
			(at 91.44 102.87 0)
			(effects
				(font
					(size 1.27 1.27)
				)
				(justify left bottom)
				(hide yes)
			)
		)
		(pin "2"
		)
		(pin "1"
		)
		(instances
			(project "com-express-7-baseboard"
				(path ""
					(reference "R143")
					(unit 1)
				)
			)
		)
	)
	(symbol
		(lib_id "antmicroResistors0402:R_0R_0402")
		(at 82.55 76.2 0)
		(unit 1)
		(exclude_from_sim no)
		(in_bom yes)
		(on_board yes)
		(dnp no)
		(property "Reference" "R150"
			(at 80.01 74.93 0)
			(effects
				(font
					(size 1.27 1.27)
					(thickness 0.15)
				)
			)
		)
		(property "Value" "R_0R_0402"
			(at 102.87 88.9 0)
			(effects
				(font
					(size 1.27 1.27)
					(thickness 0.15)
				)
				(justify left bottom)
				(hide yes)
			)
		)
		(property "Footprint" "antmicro-footprints:R_0402_1005Metric"
			(at 102.87 91.44 0)
			(effects
				(font
					(size 1.27 1.27)
					(thickness 0.15)
				)
				(justify left bottom)
				(hide yes)
			)
		)
		(property "Datasheet" "https://industrial.panasonic.com/cdbs/www-data/pdf/RDA0000/AOA0000C301.pdf"
			(at 102.87 93.98 0)
			(effects
				(font
					(size 1.27 1.27)
					(thickness 0.15)
				)
				(justify left bottom)
				(hide yes)
			)
		)
		(property "Description" ""
			(at 82.55 76.2 0)
			(effects
				(font
					(size 1.27 1.27)
				)
				(hide yes)
			)
		)
		(property "MPN" "ERJ2GE0R00X"
			(at 102.87 96.52 0)
			(effects
				(font
					(size 1.27 1.27)
					(thickness 0.15)
				)
				(justify left bottom)
				(hide yes)
			)
		)
		(property "Manufacturer" "Panasonic"
			(at 102.87 99.06 0)
			(effects
				(font
					(size 1.27 1.27)
					(thickness 0.15)
				)
				(justify left bottom)
				(hide yes)
			)
		)
		(property "License" "Apache-2.0"
			(at 102.87 101.6 0)
			(effects
				(font
					(size 1.27 1.27)
					(thickness 0.15)
				)
				(justify left bottom)
				(hide yes)
			)
		)
		(property "Author" "Antmicro"
			(at 102.87 104.14 0)
			(effects
				(font
					(size 1.27 1.27)
					(thickness 0.15)
				)
				(justify left bottom)
				(hide yes)
			)
		)
		(property "Val" "0R"
			(at 88.9 74.93 0)
			(effects
				(font
					(size 1.27 1.27)
					(thickness 0.15)
				)
			)
		)
		(property "Tolerance" "~"
			(at 102.87 86.36 0)
			(effects
				(font
					(size 1.27 1.27)
				)
				(justify left bottom)
				(hide yes)
			)
		)
		(property "Current" "1A"
			(at 102.87 106.68 0)
			(effects
				(font
					(size 1.27 1.27)
					(thickness 0.15)
				)
				(justify left bottom)
				(hide yes)
			)
		)
		(property "Public" "False"
			(at 102.87 106.68 0)
			(effects
				(font
					(size 1.27 1.27)
				)
				(justify left bottom)
				(hide yes)
			)
		)
		(pin "2"
		)
		(pin "1"
		)
		(instances
			(project "com-express-7-baseboard"
				(path ""
					(reference "R150")
					(unit 1)
				)
			)
		)
	)
	(symbol
		(lib_id "antmicroFuses:PTC_4.5A_1206")
		(at 313.69 71.12 0)
		(unit 1)
		(exclude_from_sim no)
		(in_bom yes)
		(on_board yes)
		(dnp no)
		(fields_autoplaced yes)
		(property "Reference" "F3"
			(at 316.23 66.04 0)
			(effects
				(font
					(size 1.27 1.27)
					(thickness 0.15)
				)
			)
		)
		(property "Value" "PTC_4.5A_1206"
			(at 327.66 73.66 0)
			(effects
				(font
					(size 1.27 1.27)
					(thickness 0.15)
				)
				(justify left bottom)
				(hide yes)
			)
		)
		(property "Footprint" "antmicro-footprints:F_1206_3216Metric"
			(at 327.66 76.2 0)
			(effects
				(font
					(size 1.27 1.27)
					(thickness 0.15)
				)
				(justify left bottom)
				(hide yes)
			)
		)
		(property "Datasheet" "http://www.farnell.com/datasheets/2282556.pdf"
			(at 327.66 78.74 0)
			(effects
				(font
					(size 1.27 1.27)
					(thickness 0.15)
				)
				(justify left bottom)
				(hide yes)
			)
		)
		(property "Description" ""
			(at 313.69 71.12 0)
			(effects
				(font
					(size 1.27 1.27)
				)
				(hide yes)
			)
		)
		(property "MPN" "1206L450SLWR"
			(at 316.23 68.58 0)
			(effects
				(font
					(size 1.27 1.27)
					(thickness 0.15)
				)
			)
		)
		(property "Manufacturer" "Littelfuse"
			(at 327.66 83.82 0)
			(effects
				(font
					(size 1.27 1.27)
					(thickness 0.15)
				)
				(justify left bottom)
				(hide yes)
			)
		)
		(property "Author" "Antmicro"
			(at 327.66 86.36 0)
			(effects
				(font
					(size 1.27 1.27)
					(thickness 0.15)
				)
				(justify left bottom)
				(hide yes)
			)
		)
		(property "License" "Apache-2.0"
			(at 327.66 88.9 0)
			(effects
				(font
					(size 1.27 1.27)
					(thickness 0.15)
				)
				(justify left bottom)
				(hide yes)
			)
		)
		(pin "1"
		)
		(pin "2"
		)
		(instances
			(project "com-express-7-baseboard"
				(path ""
					(reference "F3")
					(unit 1)
				)
			)
		)
	)
	(symbol
		(lib_name "R_10k_0402_1")
		(lib_id "antmicroResistors0402:R_10k_0402")
		(at 101.6 217.17 90)
		(unit 1)
		(exclude_from_sim no)
		(in_bom yes)
		(on_board yes)
		(dnp no)
		(property "Reference" "R153"
			(at 100.33 222.25 0)
			(effects
				(font
					(size 1.27 1.27)
					(thickness 0.15)
				)
				(justify left)
			)
		)
		(property "Value" "R_10k_0402"
			(at 114.3 196.85 0)
			(effects
				(font
					(size 1.27 1.27)
					(thickness 0.15)
				)
				(justify left bottom)
				(hide yes)
			)
		)
		(property "Footprint" "antmicro-footprints:R_0402_1005Metric"
			(at 116.84 196.85 0)
			(effects
				(font
					(size 1.27 1.27)
					(thickness 0.15)
				)
				(justify left bottom)
				(hide yes)
			)
		)
		(property "Datasheet" "https://www.bourns.com/docs/product-datasheets/cr.pdf"
			(at 119.38 196.85 0)
			(effects
				(font
					(size 1.27 1.27)
					(thickness 0.15)
				)
				(justify left bottom)
				(hide yes)
			)
		)
		(property "Description" "SMD Chip Resistor, 10 kohm, ± 1%, 62.5 mW, 0402 [1005 Metric], Thick Film, General Purpose"
			(at 101.6 217.17 0)
			(effects
				(font
					(size 1.27 1.27)
				)
				(hide yes)
			)
		)
		(property "MPN" "CR0402-FX-1002GLF"
			(at 121.92 196.85 0)
			(effects
				(font
					(size 1.27 1.27)
					(thickness 0.15)
				)
				(justify left bottom)
				(hide yes)
			)
		)
		(property "Manufacturer" "Bourns"
			(at 124.46 196.85 0)
			(effects
				(font
					(size 1.27 1.27)
					(thickness 0.15)
				)
				(justify left bottom)
				(hide yes)
			)
		)
		(property "License" "Apache-2.0"
			(at 127 196.85 0)
			(effects
				(font
					(size 1.27 1.27)
					(thickness 0.15)
				)
				(justify left bottom)
				(hide yes)
			)
		)
		(property "Author" "Antmicro"
			(at 129.54 196.85 0)
			(effects
				(font
					(size 1.27 1.27)
					(thickness 0.15)
				)
				(justify left bottom)
				(hide yes)
			)
		)
		(property "Val" "10k"
			(at 100.33 212.09 0)
			(effects
				(font
					(size 1.27 1.27)
					(thickness 0.15)
				)
				(justify left)
			)
		)
		(property "Tolerance" "1%"
			(at 111.76 196.85 0)
			(effects
				(font
					(size 1.27 1.27)
				)
				(justify left bottom)
				(hide yes)
			)
		)
		(pin "2"
		)
		(pin "1"
		)
		(instances
			(project "com-express-7-baseboard"
				(path ""
					(reference "R153")
					(unit 1)
				)
			)
		)
	)
	(symbol
		(lib_id "antmicroLogicTranslatorsLevelShifters:NTS0102_TSSOP")
		(at 311.15 99.06 0)
		(unit 1)
		(exclude_from_sim no)
		(in_bom yes)
		(on_board yes)
		(dnp no)
		(property "Reference" "U27"
			(at 321.31 92.71 0)
			(effects
				(font
					(size 1.27 1.27)
					(thickness 0.15)
				)
			)
		)
		(property "Value" "NTS0102_TSSOP"
			(at 321.31 93.98 0)
			(effects
				(font
					(size 1.27 1.27)
					(thickness 0.15)
				)
				(hide yes)
			)
		)
		(property "Footprint" "antmicro-footprints:TSSOP-8_3x3mm_P0.65mm"
			(at 346.71 107.95 0)
			(effects
				(font
					(size 1.27 1.27)
					(thickness 0.15)
				)
				(justify left bottom)
				(hide yes)
			)
		)
		(property "Datasheet" "https://www.mouser.com/datasheet/2/302/NTS0102-1127324.pdf"
			(at 346.71 110.49 0)
			(effects
				(font
					(size 1.27 1.27)
					(thickness 0.15)
				)
				(justify left bottom)
				(hide yes)
			)
		)
		(property "Description" ""
			(at 311.15 99.06 0)
			(effects
				(font
					(size 1.27 1.27)
				)
				(hide yes)
			)
		)
		(property "MPN" "NTS0102DP"
			(at 316.23 95.25 0)
			(effects
				(font
					(size 1.27 1.27)
					(thickness 0.15)
				)
				(justify left bottom)
			)
		)
		(property "Manufacturer" "NXP"
			(at 346.71 115.57 0)
			(effects
				(font
					(size 1.27 1.27)
					(thickness 0.15)
				)
				(justify left bottom)
				(hide yes)
			)
		)
		(property "Author" "Antmicro"
			(at 346.71 118.11 0)
			(effects
				(font
					(size 1.27 1.27)
					(thickness 0.15)
				)
				(justify left bottom)
				(hide yes)
			)
		)
		(property "License" "Apache-2.0"
			(at 346.71 120.65 0)
			(effects
				(font
					(size 1.27 1.27)
					(thickness 0.15)
				)
				(justify left bottom)
				(hide yes)
			)
		)
		(pin "3"
		)
		(pin "6"
		)
		(pin "7"
		)
		(pin "4"
		)
		(pin "5"
		)
		(pin "2"
		)
		(pin "1"
		)
		(pin "8"
		)
		(instances
			(project "com-express-7-baseboard"
				(path ""
					(reference "U27")
					(unit 1)
				)
			)
		)
	)
	(symbol
		(lib_id "antmicropower:GND")
		(at 297.18 129.54 0)
		(mirror y)
		(unit 1)
		(exclude_from_sim no)
		(in_bom yes)
		(on_board yes)
		(dnp no)
		(property "Reference" "#PWR0204"
			(at 288.29 132.08 0)
			(effects
				(font
					(size 1.27 1.27)
					(thickness 0.15)
				)
				(justify left bottom)
				(hide yes)
			)
		)
		(property "Value" "GND"
			(at 297.18 133.35 0)
			(effects
				(font
					(size 1.27 1.27)
					(thickness 0.15)
				)
			)
		)
		(property "Footprint" ""
			(at 288.29 137.16 0)
			(effects
				(font
					(size 1.27 1.27)
					(thickness 0.15)
				)
				(justify left bottom)
				(hide yes)
			)
		)
		(property "Datasheet" ""
			(at 288.29 142.24 0)
			(effects
				(font
					(size 1.27 1.27)
					(thickness 0.15)
				)
				(justify left bottom)
				(hide yes)
			)
		)
		(property "Description" ""
			(at 297.18 129.54 0)
			(effects
				(font
					(size 1.27 1.27)
				)
				(hide yes)
			)
		)
		(property "Author" "Antmicro"
			(at 288.29 137.16 0)
			(effects
				(font
					(size 1.27 1.27)
					(thickness 0.15)
				)
				(justify left bottom)
				(hide yes)
			)
		)
		(property "License" "Apache-2.0"
			(at 288.29 139.7 0)
			(effects
				(font
					(size 1.27 1.27)
					(thickness 0.15)
				)
				(justify left bottom)
				(hide yes)
			)
		)
		(pin "1"
		)
		(instances
			(project "com-express-7-baseboard"
				(path ""
					(reference "#PWR0204")
					(unit 1)
				)
			)
		)
	)
	(symbol
		(lib_id "antmicroTestPoints:TP_0.75mm_SMD")
		(at 129.54 91.44 0)
		(unit 1)
		(exclude_from_sim no)
		(in_bom no)
		(on_board yes)
		(dnp no)
		(fields_autoplaced yes)
		(property "Reference" "TP11"
			(at 134.62 91.44 0)
			(effects
				(font
					(size 1.27 1.27)
					(thickness 0.15)
				)
				(justify left)
			)
		)
		(property "Value" "TP_0.75mm_SMD"
			(at 140.335 95.25 0)
			(effects
				(font
					(size 1.27 1.27)
					(thickness 0.15)
				)
				(justify left bottom)
				(hide yes)
			)
		)
		(property "Footprint" "antmicro-footprints:TP_SMD_0.75mm"
			(at 140.335 97.79 0)
			(effects
				(font
					(size 1.27 1.27)
					(thickness 0.15)
				)
				(justify left bottom)
				(hide yes)
			)
		)
		(property "Datasheet" ""
			(at 147.32 104.14 0)
			(effects
				(font
					(size 1.27 1.27)
					(thickness 0.15)
				)
				(justify left bottom)
				(hide yes)
			)
		)
		(property "Description" ""
			(at 129.54 91.44 0)
			(effects
				(font
					(size 1.27 1.27)
				)
				(hide yes)
			)
		)
		(property "MPN" ""
			(at 140.335 102.87 0)
			(effects
				(font
					(size 1.27 1.27)
					(thickness 0.15)
				)
				(justify left bottom)
				(hide yes)
			)
		)
		(property "Manufacturer" ""
			(at 140.335 97.79 0)
			(effects
				(font
					(size 1.27 1.27)
					(thickness 0.15)
				)
				(justify left bottom)
				(hide yes)
			)
		)
		(property "Author" "Antmicro"
			(at 140.335 100.33 0)
			(effects
				(font
					(size 1.27 1.27)
					(thickness 0.15)
				)
				(justify left bottom)
				(hide yes)
			)
		)
		(property "License" "Apache-2.0"
			(at 140.335 102.87 0)
			(effects
				(font
					(size 1.27 1.27)
					(thickness 0.15)
				)
				(justify left bottom)
				(hide yes)
			)
		)
		(property "Public" "False"
			(at 139.7 105.41 0)
			(effects
				(font
					(size 1.27 1.27)
				)
				(justify left bottom)
				(hide yes)
			)
		)
		(pin "1"
		)
		(instances
			(project "com-express-7-baseboard"
				(path ""
					(reference "TP11")
					(unit 1)
				)
			)
		)
	)
	(symbol
		(lib_id "antmicropower:GND")
		(at 349.25 163.83 0)
		(unit 1)
		(exclude_from_sim no)
		(in_bom yes)
		(on_board yes)
		(dnp no)
		(property "Reference" "#PWR0221"
			(at 358.14 166.37 0)
			(effects
				(font
					(size 1.27 1.27)
					(thickness 0.15)
				)
				(justify left bottom)
				(hide yes)
			)
		)
		(property "Value" "GND"
			(at 349.25 167.64 0)
			(effects
				(font
					(size 1.27 1.27)
					(thickness 0.15)
				)
			)
		)
		(property "Footprint" ""
			(at 358.14 171.45 0)
			(effects
				(font
					(size 1.27 1.27)
					(thickness 0.15)
				)
				(justify left bottom)
				(hide yes)
			)
		)
		(property "Datasheet" ""
			(at 358.14 176.53 0)
			(effects
				(font
					(size 1.27 1.27)
					(thickness 0.15)
				)
				(justify left bottom)
				(hide yes)
			)
		)
		(property "Description" ""
			(at 349.25 163.83 0)
			(effects
				(font
					(size 1.27 1.27)
				)
				(hide yes)
			)
		)
		(property "Author" "Antmicro"
			(at 358.14 171.45 0)
			(effects
				(font
					(size 1.27 1.27)
					(thickness 0.15)
				)
				(justify left bottom)
				(hide yes)
			)
		)
		(property "License" "Apache-2.0"
			(at 358.14 173.99 0)
			(effects
				(font
					(size 1.27 1.27)
					(thickness 0.15)
				)
				(justify left bottom)
				(hide yes)
			)
		)
		(pin "1"
		)
		(instances
			(project "com-express-7-baseboard"
				(path ""
					(reference "#PWR0221")
					(unit 1)
				)
			)
		)
	)
	(symbol
		(lib_id "antmicroWire2BoardConnectors:Molex_KK_1x4_0470531000")
		(at 351.79 203.2 0)
		(unit 1)
		(exclude_from_sim no)
		(in_bom yes)
		(on_board yes)
		(dnp no)
		(property "Reference" "J11"
			(at 358.14 205.74 0)
			(effects
				(font
					(size 1.27 1.27)
					(thickness 0.15)
				)
				(justify left)
			)
		)
		(property "Value" "Molex_KK_1x4_0470531000"
			(at 372.11 213.36 0)
			(effects
				(font
					(size 1.27 1.27)
					(thickness 0.15)
				)
				(justify left bottom)
				(hide yes)
			)
		)
		(property "Footprint" "antmicro-footprints:Conn_Molex_KK_1x4_0470531000"
			(at 372.11 215.9 0)
			(effects
				(font
					(size 1.27 1.27)
					(thickness 0.15)
				)
				(justify left bottom)
				(hide yes)
			)
		)
		(property "Datasheet" "https://tools.molex.com/pdm_docs/sd/470531000_sd.pdf"
			(at 372.11 218.44 0)
			(effects
				(font
					(size 1.27 1.27)
					(thickness 0.15)
				)
				(justify left bottom)
				(hide yes)
			)
		)
		(property "Description" ""
			(at 351.79 203.2 0)
			(effects
				(font
					(size 1.27 1.27)
				)
				(hide yes)
			)
		)
		(property "MPN" "0470531000"
			(at 358.14 208.28 0)
			(effects
				(font
					(size 1.27 1.27)
					(thickness 0.15)
				)
				(justify left)
			)
		)
		(property "Manufacturer" "Molex"
			(at 372.11 220.98 0)
			(effects
				(font
					(size 1.27 1.27)
					(thickness 0.15)
				)
				(justify left bottom)
				(hide yes)
			)
		)
		(property "Author" "Antmicro"
			(at 372.11 223.52 0)
			(effects
				(font
					(size 1.27 1.27)
					(thickness 0.15)
				)
				(justify left bottom)
				(hide yes)
			)
		)
		(property "License" "Apache-2.0"
			(at 372.11 226.06 0)
			(effects
				(font
					(size 1.27 1.27)
					(thickness 0.15)
				)
				(justify left bottom)
				(hide yes)
			)
		)
		(pin "4"
		)
		(pin "3"
		)
		(pin "2"
		)
		(pin "1"
		)
		(instances
			(project "com-express-7-baseboard"
				(path ""
					(reference "J11")
					(unit 1)
				)
			)
		)
	)
	(symbol
		(lib_id "antmicroCapacitors0402:C_100n_0402")
		(at 86.36 57.15 90)
		(unit 1)
		(exclude_from_sim no)
		(in_bom yes)
		(on_board yes)
		(dnp no)
		(fields_autoplaced yes)
		(property "Reference" "C83"
			(at 83.82 53.3336 90)
			(effects
				(font
					(size 1.27 1.27)
					(thickness 0.15)
				)
				(justify left)
			)
		)
		(property "Value" "C_100n_0402"
			(at 96.52 36.83 0)
			(effects
				(font
					(size 1.27 1.27)
					(thickness 0.15)
				)
				(justify left bottom)
				(hide yes)
			)
		)
		(property "Footprint" "antmicro-footprints:C_0402_1005Metric"
			(at 99.06 36.83 0)
			(effects
				(font
					(size 1.27 1.27)
					(thickness 0.15)
				)
				(justify left bottom)
				(hide yes)
			)
		)
		(property "Datasheet" "https://www.murata.com/products/productdetail?partno=GRM155R61H104KE14%23"
			(at 101.6 36.83 0)
			(effects
				(font
					(size 1.27 1.27)
					(thickness 0.15)
				)
				(justify left bottom)
				(hide yes)
			)
		)
		(property "Description" ""
			(at 86.36 57.15 0)
			(effects
				(font
					(size 1.27 1.27)
				)
				(hide yes)
			)
		)
		(property "MPN" "GRM155R61H104KE14D"
			(at 104.14 36.83 0)
			(effects
				(font
					(size 1.27 1.27)
					(thickness 0.15)
				)
				(justify left bottom)
				(hide yes)
			)
		)
		(property "Manufacturer" "Murata"
			(at 106.68 36.83 0)
			(effects
				(font
					(size 1.27 1.27)
					(thickness 0.15)
				)
				(justify left bottom)
				(hide yes)
			)
		)
		(property "License" "Apache-2.0"
			(at 109.22 36.83 0)
			(effects
				(font
					(size 1.27 1.27)
					(thickness 0.15)
				)
				(justify left bottom)
				(hide yes)
			)
		)
		(property "Author" "Antmicro"
			(at 111.76 36.83 0)
			(effects
				(font
					(size 1.27 1.27)
					(thickness 0.15)
				)
				(justify left bottom)
				(hide yes)
			)
		)
		(property "Val" "100n"
			(at 83.82 55.8736 90)
			(effects
				(font
					(size 1.27 1.27)
					(thickness 0.15)
				)
				(justify left)
			)
		)
		(property "Voltage" "50V"
			(at 114.3 36.83 0)
			(effects
				(font
					(size 1.27 1.27)
				)
				(justify left bottom)
				(hide yes)
			)
		)
		(property "Dielectric" "X5R"
			(at 116.84 36.83 0)
			(effects
				(font
					(size 1.27 1.27)
				)
				(justify left bottom)
				(hide yes)
			)
		)
		(property "Public" "False"
			(at 119.38 36.83 0)
			(effects
				(font
					(size 1.27 1.27)
				)
				(justify left bottom)
				(hide yes)
			)
		)
		(pin "2"
		)
		(pin "1"
		)
		(instances
			(project "com-express-7-baseboard"
				(path ""
					(reference "C83")
					(unit 1)
				)
			)
		)
	)
	(symbol
		(lib_id "antmicropower:GND")
		(at 349.25 214.63 0)
		(unit 1)
		(exclude_from_sim no)
		(in_bom yes)
		(on_board yes)
		(dnp no)
		(property "Reference" "#PWR0222"
			(at 358.14 217.17 0)
			(effects
				(font
					(size 1.27 1.27)
					(thickness 0.15)
				)
				(justify left bottom)
				(hide yes)
			)
		)
		(property "Value" "GND"
			(at 349.25 218.44 0)
			(effects
				(font
					(size 1.27 1.27)
					(thickness 0.15)
				)
			)
		)
		(property "Footprint" ""
			(at 358.14 222.25 0)
			(effects
				(font
					(size 1.27 1.27)
					(thickness 0.15)
				)
				(justify left bottom)
				(hide yes)
			)
		)
		(property "Datasheet" ""
			(at 358.14 227.33 0)
			(effects
				(font
					(size 1.27 1.27)
					(thickness 0.15)
				)
				(justify left bottom)
				(hide yes)
			)
		)
		(property "Description" ""
			(at 349.25 214.63 0)
			(effects
				(font
					(size 1.27 1.27)
				)
				(hide yes)
			)
		)
		(property "Author" "Antmicro"
			(at 358.14 222.25 0)
			(effects
				(font
					(size 1.27 1.27)
					(thickness 0.15)
				)
				(justify left bottom)
				(hide yes)
			)
		)
		(property "License" "Apache-2.0"
			(at 358.14 224.79 0)
			(effects
				(font
					(size 1.27 1.27)
					(thickness 0.15)
				)
				(justify left bottom)
				(hide yes)
			)
		)
		(pin "1"
		)
		(instances
			(project "com-express-7-baseboard"
				(path ""
					(reference "#PWR0222")
					(unit 1)
				)
			)
		)
	)
	(symbol
		(lib_id "antmicropower:+3V3")
		(at 307.34 88.9 0)
		(unit 1)
		(exclude_from_sim no)
		(in_bom yes)
		(on_board yes)
		(dnp no)
		(property "Reference" "#PWR0207"
			(at 322.58 88.9 0)
			(effects
				(font
					(size 1.27 1.27)
					(thickness 0.15)
				)
				(justify left bottom)
				(hide yes)
			)
		)
		(property "Value" "+3V3"
			(at 307.34 85.09 0)
			(effects
				(font
					(size 1.27 1.27)
					(thickness 0.15)
				)
			)
		)
		(property "Footprint" ""
			(at 322.58 96.52 0)
			(effects
				(font
					(size 1.27 1.27)
					(thickness 0.15)
				)
				(justify left bottom)
				(hide yes)
			)
		)
		(property "Datasheet" ""
			(at 322.58 99.06 0)
			(effects
				(font
					(size 1.27 1.27)
					(thickness 0.15)
				)
				(justify left bottom)
				(hide yes)
			)
		)
		(property "Description" ""
			(at 307.34 88.9 0)
			(effects
				(font
					(size 1.27 1.27)
				)
				(hide yes)
			)
		)
		(property "Author" "Antmicro"
			(at 322.58 91.44 0)
			(effects
				(font
					(size 1.27 1.27)
					(thickness 0.15)
				)
				(justify left bottom)
				(hide yes)
			)
		)
		(property "License" "Apache-2.0"
			(at 322.58 93.98 0)
			(effects
				(font
					(size 1.27 1.27)
					(thickness 0.15)
				)
				(justify left bottom)
				(hide yes)
			)
		)
		(pin "1"
		)
		(instances
			(project "com-express-7-baseboard"
				(path ""
					(reference "#PWR0207")
					(unit 1)
				)
			)
		)
	)
	(symbol
		(lib_id "antmicropower:GND")
		(at 60.96 123.19 0)
		(unit 1)
		(exclude_from_sim no)
		(in_bom yes)
		(on_board yes)
		(dnp no)
		(property "Reference" "#PWR0440"
			(at 69.85 125.73 0)
			(effects
				(font
					(size 1.27 1.27)
					(thickness 0.15)
				)
				(justify left bottom)
				(hide yes)
			)
		)
		(property "Value" "GND"
			(at 60.96 127 0)
			(effects
				(font
					(size 1.27 1.27)
					(thickness 0.15)
				)
			)
		)
		(property "Footprint" ""
			(at 69.85 130.81 0)
			(effects
				(font
					(size 1.27 1.27)
					(thickness 0.15)
				)
				(justify left bottom)
				(hide yes)
			)
		)
		(property "Datasheet" ""
			(at 69.85 135.89 0)
			(effects
				(font
					(size 1.27 1.27)
					(thickness 0.15)
				)
				(justify left bottom)
				(hide yes)
			)
		)
		(property "Description" ""
			(at 60.96 123.19 0)
			(effects
				(font
					(size 1.27 1.27)
				)
				(hide yes)
			)
		)
		(property "Author" "Antmicro"
			(at 69.85 130.81 0)
			(effects
				(font
					(size 1.27 1.27)
					(thickness 0.15)
				)
				(justify left bottom)
				(hide yes)
			)
		)
		(property "License" "Apache-2.0"
			(at 69.85 133.35 0)
			(effects
				(font
					(size 1.27 1.27)
					(thickness 0.15)
				)
				(justify left bottom)
				(hide yes)
			)
		)
		(pin "1"
		)
		(instances
			(project "com-express-7-baseboard"
				(path ""
					(reference "#PWR0440")
					(unit 1)
				)
			)
		)
	)
	(symbol
		(lib_id "antmicropower:GND")
		(at 101.6 251.46 0)
		(mirror y)
		(unit 1)
		(exclude_from_sim no)
		(in_bom yes)
		(on_board yes)
		(dnp no)
		(property "Reference" "#PWR0197"
			(at 92.71 254 0)
			(effects
				(font
					(size 1.27 1.27)
					(thickness 0.15)
				)
				(justify left bottom)
				(hide yes)
			)
		)
		(property "Value" "GND"
			(at 101.6 255.27 0)
			(effects
				(font
					(size 1.27 1.27)
					(thickness 0.15)
				)
			)
		)
		(property "Footprint" ""
			(at 92.71 259.08 0)
			(effects
				(font
					(size 1.27 1.27)
					(thickness 0.15)
				)
				(justify left bottom)
				(hide yes)
			)
		)
		(property "Datasheet" ""
			(at 92.71 264.16 0)
			(effects
				(font
					(size 1.27 1.27)
					(thickness 0.15)
				)
				(justify left bottom)
				(hide yes)
			)
		)
		(property "Description" ""
			(at 101.6 251.46 0)
			(effects
				(font
					(size 1.27 1.27)
				)
				(hide yes)
			)
		)
		(property "Author" "Antmicro"
			(at 92.71 259.08 0)
			(effects
				(font
					(size 1.27 1.27)
					(thickness 0.15)
				)
				(justify left bottom)
				(hide yes)
			)
		)
		(property "License" "Apache-2.0"
			(at 92.71 261.62 0)
			(effects
				(font
					(size 1.27 1.27)
					(thickness 0.15)
				)
				(justify left bottom)
				(hide yes)
			)
		)
		(pin "1"
		)
		(instances
			(project "com-express-7-baseboard"
				(path ""
					(reference "#PWR0197")
					(unit 1)
				)
			)
		)
	)
	(symbol
		(lib_id "antmicroTransistorsFETsMOSFETsSingle:BSS84AKW")
		(at 71.12 41.91 270)
		(mirror x)
		(unit 1)
		(exclude_from_sim no)
		(in_bom yes)
		(on_board yes)
		(dnp no)
		(property "Reference" "Q6"
			(at 73.66 27.94 90)
			(effects
				(font
					(size 1.27 1.27)
					(thickness 0.15)
				)
			)
		)
		(property "Value" "BSS84AKW"
			(at 63.5 19.05 0)
			(effects
				(font
					(size 1.27 1.27)
					(thickness 0.15)
				)
				(justify left bottom)
				(hide yes)
			)
		)
		(property "Footprint" "antmicro-footprints:SOT-323"
			(at 60.96 19.05 0)
			(effects
				(font
					(size 1.27 1.27)
					(thickness 0.15)
				)
				(justify left bottom)
				(hide yes)
			)
		)
		(property "Datasheet" "https://assets.nexperia.com/documents/data-sheet/BSS84AKW.pdf"
			(at 58.42 19.05 0)
			(effects
				(font
					(size 1.27 1.27)
					(thickness 0.15)
				)
				(justify left bottom)
				(hide yes)
			)
		)
		(property "Description" ""
			(at 71.12 41.91 0)
			(effects
				(font
					(size 1.27 1.27)
				)
				(hide yes)
			)
		)
		(property "MPN" "BSS84AKW,115"
			(at 73.66 30.48 90)
			(effects
				(font
					(size 1.27 1.27)
					(thickness 0.15)
				)
			)
		)
		(property "Manufacturer" "Nexperia"
			(at 55.88 19.05 0)
			(effects
				(font
					(size 1.27 1.27)
					(thickness 0.15)
				)
				(justify left bottom)
				(hide yes)
			)
		)
		(property "Author" "Antmicro"
			(at 53.34 19.05 0)
			(effects
				(font
					(size 1.27 1.27)
					(thickness 0.15)
				)
				(justify left bottom)
				(hide yes)
			)
		)
		(property "License" "Apache-2.0"
			(at 50.8 19.05 0)
			(effects
				(font
					(size 1.27 1.27)
					(thickness 0.15)
				)
				(justify left bottom)
				(hide yes)
			)
		)
		(pin "2"
		)
		(pin "1"
		)
		(pin "3"
		)
		(instances
			(project "com-express-7-baseboard"
				(path ""
					(reference "Q6")
					(unit 1)
				)
			)
		)
	)
	(symbol
		(lib_id "antmicroCapacitors0402:C_100n_0402")
		(at 307.34 154.94 270)
		(mirror x)
		(unit 1)
		(exclude_from_sim no)
		(in_bom yes)
		(on_board yes)
		(dnp no)
		(fields_autoplaced yes)
		(property "Reference" "C87"
			(at 304.8 151.1236 90)
			(effects
				(font
					(size 1.27 1.27)
					(thickness 0.15)
				)
				(justify right)
			)
		)
		(property "Value" "C_100n_0402"
			(at 297.18 134.62 0)
			(effects
				(font
					(size 1.27 1.27)
					(thickness 0.15)
				)
				(justify left bottom)
				(hide yes)
			)
		)
		(property "Footprint" "antmicro-footprints:C_0402_1005Metric"
			(at 294.64 134.62 0)
			(effects
				(font
					(size 1.27 1.27)
					(thickness 0.15)
				)
				(justify left bottom)
				(hide yes)
			)
		)
		(property "Datasheet" "https://www.murata.com/products/productdetail?partno=GRM155R61H104KE14%23"
			(at 292.1 134.62 0)
			(effects
				(font
					(size 1.27 1.27)
					(thickness 0.15)
				)
				(justify left bottom)
				(hide yes)
			)
		)
		(property "Description" ""
			(at 307.34 154.94 0)
			(effects
				(font
					(size 1.27 1.27)
				)
				(hide yes)
			)
		)
		(property "MPN" "GRM155R61H104KE14D"
			(at 289.56 134.62 0)
			(effects
				(font
					(size 1.27 1.27)
					(thickness 0.15)
				)
				(justify left bottom)
				(hide yes)
			)
		)
		(property "Manufacturer" "Murata"
			(at 287.02 134.62 0)
			(effects
				(font
					(size 1.27 1.27)
					(thickness 0.15)
				)
				(justify left bottom)
				(hide yes)
			)
		)
		(property "License" "Apache-2.0"
			(at 284.48 134.62 0)
			(effects
				(font
					(size 1.27 1.27)
					(thickness 0.15)
				)
				(justify left bottom)
				(hide yes)
			)
		)
		(property "Author" "Antmicro"
			(at 281.94 134.62 0)
			(effects
				(font
					(size 1.27 1.27)
					(thickness 0.15)
				)
				(justify left bottom)
				(hide yes)
			)
		)
		(property "Val" "100n"
			(at 304.8 153.6636 90)
			(effects
				(font
					(size 1.27 1.27)
					(thickness 0.15)
				)
				(justify right)
			)
		)
		(property "Voltage" "50V"
			(at 279.4 134.62 0)
			(effects
				(font
					(size 1.27 1.27)
				)
				(justify left bottom)
				(hide yes)
			)
		)
		(property "Dielectric" "X5R"
			(at 276.86 134.62 0)
			(effects
				(font
					(size 1.27 1.27)
				)
				(justify left bottom)
				(hide yes)
			)
		)
		(property "Public" "False"
			(at 274.32 134.62 0)
			(effects
				(font
					(size 1.27 1.27)
				)
				(justify left bottom)
				(hide yes)
			)
		)
		(pin "2"
		)
		(pin "1"
		)
		(instances
			(project "com-express-7-baseboard"
				(path ""
					(reference "C87")
					(unit 1)
				)
			)
		)
	)
	(symbol
		(lib_id "antmicroResistors0402:R_0R_0402")
		(at 82.55 71.12 0)
		(unit 1)
		(exclude_from_sim no)
		(in_bom yes)
		(on_board yes)
		(dnp no)
		(property "Reference" "R148"
			(at 80.01 69.85 0)
			(effects
				(font
					(size 1.27 1.27)
					(thickness 0.15)
				)
			)
		)
		(property "Value" "R_0R_0402"
			(at 102.87 83.82 0)
			(effects
				(font
					(size 1.27 1.27)
					(thickness 0.15)
				)
				(justify left bottom)
				(hide yes)
			)
		)
		(property "Footprint" "antmicro-footprints:R_0402_1005Metric"
			(at 102.87 86.36 0)
			(effects
				(font
					(size 1.27 1.27)
					(thickness 0.15)
				)
				(justify left bottom)
				(hide yes)
			)
		)
		(property "Datasheet" "https://industrial.panasonic.com/cdbs/www-data/pdf/RDA0000/AOA0000C301.pdf"
			(at 102.87 88.9 0)
			(effects
				(font
					(size 1.27 1.27)
					(thickness 0.15)
				)
				(justify left bottom)
				(hide yes)
			)
		)
		(property "Description" ""
			(at 82.55 71.12 0)
			(effects
				(font
					(size 1.27 1.27)
				)
				(hide yes)
			)
		)
		(property "MPN" "ERJ2GE0R00X"
			(at 102.87 91.44 0)
			(effects
				(font
					(size 1.27 1.27)
					(thickness 0.15)
				)
				(justify left bottom)
				(hide yes)
			)
		)
		(property "Manufacturer" "Panasonic"
			(at 102.87 93.98 0)
			(effects
				(font
					(size 1.27 1.27)
					(thickness 0.15)
				)
				(justify left bottom)
				(hide yes)
			)
		)
		(property "License" "Apache-2.0"
			(at 102.87 96.52 0)
			(effects
				(font
					(size 1.27 1.27)
					(thickness 0.15)
				)
				(justify left bottom)
				(hide yes)
			)
		)
		(property "Author" "Antmicro"
			(at 102.87 99.06 0)
			(effects
				(font
					(size 1.27 1.27)
					(thickness 0.15)
				)
				(justify left bottom)
				(hide yes)
			)
		)
		(property "Val" "0R"
			(at 88.9 69.85 0)
			(effects
				(font
					(size 1.27 1.27)
					(thickness 0.15)
				)
			)
		)
		(property "Tolerance" "~"
			(at 102.87 81.28 0)
			(effects
				(font
					(size 1.27 1.27)
				)
				(justify left bottom)
				(hide yes)
			)
		)
		(property "Current" "1A"
			(at 102.87 101.6 0)
			(effects
				(font
					(size 1.27 1.27)
					(thickness 0.15)
				)
				(justify left bottom)
				(hide yes)
			)
		)
		(property "Public" "False"
			(at 102.87 101.6 0)
			(effects
				(font
					(size 1.27 1.27)
				)
				(justify left bottom)
				(hide yes)
			)
		)
		(pin "2"
		)
		(pin "1"
		)
		(instances
			(project "com-express-7-baseboard"
				(path ""
					(reference "R148")
					(unit 1)
				)
			)
		)
	)
	(symbol
		(lib_id "antmicroWire2BoardConnectors:Molex_KK_1x4_0470531000")
		(at 353.06 96.52 0)
		(unit 1)
		(exclude_from_sim no)
		(in_bom yes)
		(on_board yes)
		(dnp no)
		(property "Reference" "J9"
			(at 359.41 99.06 0)
			(effects
				(font
					(size 1.27 1.27)
					(thickness 0.15)
				)
				(justify left)
			)
		)
		(property "Value" "Molex_KK_1x4_0470531000"
			(at 373.38 106.68 0)
			(effects
				(font
					(size 1.27 1.27)
					(thickness 0.15)
				)
				(justify left bottom)
				(hide yes)
			)
		)
		(property "Footprint" "antmicro-footprints:Conn_Molex_KK_1x4_0470531000"
			(at 373.38 109.22 0)
			(effects
				(font
					(size 1.27 1.27)
					(thickness 0.15)
				)
				(justify left bottom)
				(hide yes)
			)
		)
		(property "Datasheet" "https://tools.molex.com/pdm_docs/sd/470531000_sd.pdf"
			(at 373.38 111.76 0)
			(effects
				(font
					(size 1.27 1.27)
					(thickness 0.15)
				)
				(justify left bottom)
				(hide yes)
			)
		)
		(property "Description" ""
			(at 353.06 96.52 0)
			(effects
				(font
					(size 1.27 1.27)
				)
				(hide yes)
			)
		)
		(property "MPN" "0470531000"
			(at 359.41 101.6 0)
			(effects
				(font
					(size 1.27 1.27)
					(thickness 0.15)
				)
				(justify left)
			)
		)
		(property "Manufacturer" "Molex"
			(at 373.38 114.3 0)
			(effects
				(font
					(size 1.27 1.27)
					(thickness 0.15)
				)
				(justify left bottom)
				(hide yes)
			)
		)
		(property "Author" "Antmicro"
			(at 373.38 116.84 0)
			(effects
				(font
					(size 1.27 1.27)
					(thickness 0.15)
				)
				(justify left bottom)
				(hide yes)
			)
		)
		(property "License" "Apache-2.0"
			(at 373.38 119.38 0)
			(effects
				(font
					(size 1.27 1.27)
					(thickness 0.15)
				)
				(justify left bottom)
				(hide yes)
			)
		)
		(pin "4"
		)
		(pin "3"
		)
		(pin "2"
		)
		(pin "1"
		)
		(instances
			(project "com-express-7-baseboard"
				(path ""
					(reference "J9")
					(unit 1)
				)
			)
		)
	)
	(symbol
		(lib_id "antmicroResistors0402:R_10k_0402")
		(at 69.85 123.19 90)
		(unit 1)
		(exclude_from_sim no)
		(in_bom yes)
		(on_board yes)
		(dnp yes)
		(property "Reference" "R146"
			(at 71.12 118.11 90)
			(effects
				(font
					(size 1.27 1.27)
					(thickness 0.15)
				)
				(justify right)
			)
		)
		(property "Value" "R_10k_0402"
			(at 82.55 102.87 0)
			(effects
				(font
					(size 1.27 1.27)
					(thickness 0.15)
				)
				(justify left bottom)
				(hide yes)
			)
		)
		(property "Footprint" "antmicro-footprints:R_0402_1005Metric"
			(at 85.09 102.87 0)
			(effects
				(font
					(size 1.27 1.27)
					(thickness 0.15)
				)
				(justify left bottom)
				(hide yes)
			)
		)
		(property "Datasheet" "https://www.bourns.com/docs/product-datasheets/cr.pdf"
			(at 87.63 102.87 0)
			(effects
				(font
					(size 1.27 1.27)
					(thickness 0.15)
				)
				(justify left bottom)
				(hide yes)
			)
		)
		(property "Description" ""
			(at 69.85 123.19 0)
			(effects
				(font
					(size 1.27 1.27)
				)
				(hide yes)
			)
		)
		(property "MPN" "CR0402-FX-1002GLF"
			(at 90.17 102.87 0)
			(effects
				(font
					(size 1.27 1.27)
					(thickness 0.15)
				)
				(justify left bottom)
				(hide yes)
			)
		)
		(property "Manufacturer" "Bourns"
			(at 92.71 102.87 0)
			(effects
				(font
					(size 1.27 1.27)
					(thickness 0.15)
				)
				(justify left bottom)
				(hide yes)
			)
		)
		(property "License" "Apache-2.0"
			(at 95.25 102.87 0)
			(effects
				(font
					(size 1.27 1.27)
					(thickness 0.15)
				)
				(justify left bottom)
				(hide yes)
			)
		)
		(property "Author" "Antmicro"
			(at 97.79 102.87 0)
			(effects
				(font
					(size 1.27 1.27)
					(thickness 0.15)
				)
				(justify left bottom)
				(hide yes)
			)
		)
		(property "Val" "10k"
			(at 71.12 120.65 90)
			(effects
				(font
					(size 1.27 1.27)
					(thickness 0.15)
				)
				(justify right)
			)
		)
		(property "Tolerance" "1%"
			(at 80.01 102.87 0)
			(effects
				(font
					(size 1.27 1.27)
				)
				(justify left bottom)
				(hide yes)
			)
		)
		(property "Public" "False"
			(at 100.33 102.87 0)
			(effects
				(font
					(size 1.27 1.27)
				)
				(justify left bottom)
				(hide yes)
			)
		)
		(pin "1"
		)
		(pin "2"
		)
		(instances
			(project "com-express-7-baseboard"
				(path ""
					(reference "R146")
					(unit 1)
				)
			)
		)
	)
	(symbol
		(lib_id "antmicroCapacitors0402:C_100n_0402")
		(at 307.34 99.06 270)
		(mirror x)
		(unit 1)
		(exclude_from_sim no)
		(in_bom yes)
		(on_board yes)
		(dnp no)
		(fields_autoplaced yes)
		(property "Reference" "C86"
			(at 304.8 95.2436 90)
			(effects
				(font
					(size 1.27 1.27)
					(thickness 0.15)
				)
				(justify right)
			)
		)
		(property "Value" "C_100n_0402"
			(at 297.18 78.74 0)
			(effects
				(font
					(size 1.27 1.27)
					(thickness 0.15)
				)
				(justify left bottom)
				(hide yes)
			)
		)
		(property "Footprint" "antmicro-footprints:C_0402_1005Metric"
			(at 294.64 78.74 0)
			(effects
				(font
					(size 1.27 1.27)
					(thickness 0.15)
				)
				(justify left bottom)
				(hide yes)
			)
		)
		(property "Datasheet" "https://www.murata.com/products/productdetail?partno=GRM155R61H104KE14%23"
			(at 292.1 78.74 0)
			(effects
				(font
					(size 1.27 1.27)
					(thickness 0.15)
				)
				(justify left bottom)
				(hide yes)
			)
		)
		(property "Description" ""
			(at 307.34 99.06 0)
			(effects
				(font
					(size 1.27 1.27)
				)
				(hide yes)
			)
		)
		(property "MPN" "GRM155R61H104KE14D"
			(at 289.56 78.74 0)
			(effects
				(font
					(size 1.27 1.27)
					(thickness 0.15)
				)
				(justify left bottom)
				(hide yes)
			)
		)
		(property "Manufacturer" "Murata"
			(at 287.02 78.74 0)
			(effects
				(font
					(size 1.27 1.27)
					(thickness 0.15)
				)
				(justify left bottom)
				(hide yes)
			)
		)
		(property "License" "Apache-2.0"
			(at 284.48 78.74 0)
			(effects
				(font
					(size 1.27 1.27)
					(thickness 0.15)
				)
				(justify left bottom)
				(hide yes)
			)
		)
		(property "Author" "Antmicro"
			(at 281.94 78.74 0)
			(effects
				(font
					(size 1.27 1.27)
					(thickness 0.15)
				)
				(justify left bottom)
				(hide yes)
			)
		)
		(property "Val" "100n"
			(at 304.8 97.7836 90)
			(effects
				(font
					(size 1.27 1.27)
					(thickness 0.15)
				)
				(justify right)
			)
		)
		(property "Voltage" "50V"
			(at 279.4 78.74 0)
			(effects
				(font
					(size 1.27 1.27)
				)
				(justify left bottom)
				(hide yes)
			)
		)
		(property "Dielectric" "X5R"
			(at 276.86 78.74 0)
			(effects
				(font
					(size 1.27 1.27)
				)
				(justify left bottom)
				(hide yes)
			)
		)
		(property "Public" "False"
			(at 274.32 78.74 0)
			(effects
				(font
					(size 1.27 1.27)
				)
				(justify left bottom)
				(hide yes)
			)
		)
		(pin "2"
		)
		(pin "1"
		)
		(instances
			(project "com-express-7-baseboard"
				(path ""
					(reference "C86")
					(unit 1)
				)
			)
		)
	)
	(symbol
		(lib_id "antmicropower:+5V")
		(at 335.28 88.9 0)
		(unit 1)
		(exclude_from_sim no)
		(in_bom yes)
		(on_board yes)
		(dnp no)
		(property "Reference" "#PWR0214"
			(at 350.52 91.44 0)
			(effects
				(font
					(size 1.27 1.27)
					(thickness 0.15)
				)
				(justify left bottom)
				(hide yes)
			)
		)
		(property "Value" "+5V"
			(at 335.28 85.09 0)
			(effects
				(font
					(size 1.27 1.27)
					(thickness 0.15)
				)
			)
		)
		(property "Footprint" ""
			(at 350.52 96.52 0)
			(effects
				(font
					(size 1.27 1.27)
					(thickness 0.15)
				)
				(justify left bottom)
				(hide yes)
			)
		)
		(property "Datasheet" ""
			(at 350.52 99.06 0)
			(effects
				(font
					(size 1.27 1.27)
					(thickness 0.15)
				)
				(justify left bottom)
				(hide yes)
			)
		)
		(property "Description" ""
			(at 335.28 88.9 0)
			(effects
				(font
					(size 1.27 1.27)
				)
				(hide yes)
			)
		)
		(property "Author" "Antmicro"
			(at 350.52 96.52 0)
			(effects
				(font
					(size 1.27 1.27)
					(thickness 0.15)
				)
				(justify left bottom)
				(hide yes)
			)
		)
		(property "License" "Apache-2.0"
			(at 350.52 99.06 0)
			(effects
				(font
					(size 1.27 1.27)
					(thickness 0.15)
				)
				(justify left bottom)
				(hide yes)
			)
		)
		(pin "1"
		)
		(instances
			(project "com-express-7-baseboard"
				(path ""
					(reference "#PWR0214")
					(unit 1)
				)
			)
		)
	)
	(symbol
		(lib_id "antmicroResistors0402:R_10k_0402")
		(at 157.48 86.36 90)
		(unit 1)
		(exclude_from_sim no)
		(in_bom yes)
		(on_board yes)
		(dnp no)
		(fields_autoplaced yes)
		(property "Reference" "R157"
			(at 160.02 82.55 90)
			(effects
				(font
					(size 1.27 1.27)
					(thickness 0.15)
				)
				(justify right)
			)
		)
		(property "Value" "R_10k_0402"
			(at 170.18 66.04 0)
			(effects
				(font
					(size 1.27 1.27)
					(thickness 0.15)
				)
				(justify left bottom)
				(hide yes)
			)
		)
		(property "Footprint" "antmicro-footprints:R_0402_1005Metric"
			(at 172.72 66.04 0)
			(effects
				(font
					(size 1.27 1.27)
					(thickness 0.15)
				)
				(justify left bottom)
				(hide yes)
			)
		)
		(property "Datasheet" "https://www.bourns.com/docs/product-datasheets/cr.pdf"
			(at 175.26 66.04 0)
			(effects
				(font
					(size 1.27 1.27)
					(thickness 0.15)
				)
				(justify left bottom)
				(hide yes)
			)
		)
		(property "Description" ""
			(at 157.48 86.36 0)
			(effects
				(font
					(size 1.27 1.27)
				)
				(hide yes)
			)
		)
		(property "MPN" "CR0402-FX-1002GLF"
			(at 177.8 66.04 0)
			(effects
				(font
					(size 1.27 1.27)
					(thickness 0.15)
				)
				(justify left bottom)
				(hide yes)
			)
		)
		(property "Manufacturer" "Bourns"
			(at 180.34 66.04 0)
			(effects
				(font
					(size 1.27 1.27)
					(thickness 0.15)
				)
				(justify left bottom)
				(hide yes)
			)
		)
		(property "License" "Apache-2.0"
			(at 182.88 66.04 0)
			(effects
				(font
					(size 1.27 1.27)
					(thickness 0.15)
				)
				(justify left bottom)
				(hide yes)
			)
		)
		(property "Author" "Antmicro"
			(at 185.42 66.04 0)
			(effects
				(font
					(size 1.27 1.27)
					(thickness 0.15)
				)
				(justify left bottom)
				(hide yes)
			)
		)
		(property "Val" "10k"
			(at 160.02 85.09 90)
			(effects
				(font
					(size 1.27 1.27)
					(thickness 0.15)
				)
				(justify right)
			)
		)
		(property "Tolerance" "1%"
			(at 167.64 66.04 0)
			(effects
				(font
					(size 1.27 1.27)
				)
				(justify left bottom)
				(hide yes)
			)
		)
		(property "Public" "False"
			(at 187.96 66.04 0)
			(effects
				(font
					(size 1.27 1.27)
				)
				(justify left bottom)
				(hide yes)
			)
		)
		(pin "1"
		)
		(pin "2"
		)
		(instances
			(project "com-express-7-baseboard"
				(path ""
					(reference "R157")
					(unit 1)
				)
			)
		)
	)
	(symbol
		(lib_id "antmicroResistors0402:R_10k_0402")
		(at 146.05 78.74 270)
		(mirror x)
		(unit 1)
		(exclude_from_sim no)
		(in_bom yes)
		(on_board yes)
		(dnp no)
		(property "Reference" "R155"
			(at 144.78 74.93 90)
			(effects
				(font
					(size 1.27 1.27)
					(thickness 0.15)
				)
				(justify right)
			)
		)
		(property "Value" "R_10k_0402"
			(at 133.35 58.42 0)
			(effects
				(font
					(size 1.27 1.27)
					(thickness 0.15)
				)
				(justify left bottom)
				(hide yes)
			)
		)
		(property "Footprint" "antmicro-footprints:R_0402_1005Metric"
			(at 130.81 58.42 0)
			(effects
				(font
					(size 1.27 1.27)
					(thickness 0.15)
				)
				(justify left bottom)
				(hide yes)
			)
		)
		(property "Datasheet" "https://www.bourns.com/docs/product-datasheets/cr.pdf"
			(at 128.27 58.42 0)
			(effects
				(font
					(size 1.27 1.27)
					(thickness 0.15)
				)
				(justify left bottom)
				(hide yes)
			)
		)
		(property "Description" ""
			(at 146.05 78.74 0)
			(effects
				(font
					(size 1.27 1.27)
				)
				(hide yes)
			)
		)
		(property "MPN" "CR0402-FX-1002GLF"
			(at 125.73 58.42 0)
			(effects
				(font
					(size 1.27 1.27)
					(thickness 0.15)
				)
				(justify left bottom)
				(hide yes)
			)
		)
		(property "Manufacturer" "Bourns"
			(at 123.19 58.42 0)
			(effects
				(font
					(size 1.27 1.27)
					(thickness 0.15)
				)
				(justify left bottom)
				(hide yes)
			)
		)
		(property "License" "Apache-2.0"
			(at 120.65 58.42 0)
			(effects
				(font
					(size 1.27 1.27)
					(thickness 0.15)
				)
				(justify left bottom)
				(hide yes)
			)
		)
		(property "Author" "Antmicro"
			(at 118.11 58.42 0)
			(effects
				(font
					(size 1.27 1.27)
					(thickness 0.15)
				)
				(justify left bottom)
				(hide yes)
			)
		)
		(property "Val" "10k"
			(at 144.78 77.47 90)
			(effects
				(font
					(size 1.27 1.27)
					(thickness 0.15)
				)
				(justify right)
			)
		)
		(property "Tolerance" "1%"
			(at 135.89 58.42 0)
			(effects
				(font
					(size 1.27 1.27)
				)
				(justify left bottom)
				(hide yes)
			)
		)
		(property "Public" "False"
			(at 115.57 58.42 0)
			(effects
				(font
					(size 1.27 1.27)
				)
				(justify left bottom)
				(hide yes)
			)
		)
		(pin "1"
		)
		(pin "2"
		)
		(instances
			(project "com-express-7-baseboard"
				(path ""
					(reference "R155")
					(unit 1)
				)
			)
		)
	)
	(symbol
		(lib_id "antmicroTestPoints:TP_0.75mm_SMD")
		(at 129.54 99.06 0)
		(unit 1)
		(exclude_from_sim no)
		(in_bom no)
		(on_board yes)
		(dnp no)
		(fields_autoplaced yes)
		(property "Reference" "TP14"
			(at 134.62 99.06 0)
			(effects
				(font
					(size 1.27 1.27)
					(thickness 0.15)
				)
				(justify left)
			)
		)
		(property "Value" "TP_0.75mm_SMD"
			(at 140.335 102.87 0)
			(effects
				(font
					(size 1.27 1.27)
					(thickness 0.15)
				)
				(justify left bottom)
				(hide yes)
			)
		)
		(property "Footprint" "antmicro-footprints:TP_SMD_0.75mm"
			(at 140.335 105.41 0)
			(effects
				(font
					(size 1.27 1.27)
					(thickness 0.15)
				)
				(justify left bottom)
				(hide yes)
			)
		)
		(property "Datasheet" ""
			(at 147.32 111.76 0)
			(effects
				(font
					(size 1.27 1.27)
					(thickness 0.15)
				)
				(justify left bottom)
				(hide yes)
			)
		)
		(property "Description" ""
			(at 129.54 99.06 0)
			(effects
				(font
					(size 1.27 1.27)
				)
				(hide yes)
			)
		)
		(property "MPN" ""
			(at 140.335 110.49 0)
			(effects
				(font
					(size 1.27 1.27)
					(thickness 0.15)
				)
				(justify left bottom)
				(hide yes)
			)
		)
		(property "Manufacturer" ""
			(at 140.335 105.41 0)
			(effects
				(font
					(size 1.27 1.27)
					(thickness 0.15)
				)
				(justify left bottom)
				(hide yes)
			)
		)
		(property "Author" "Antmicro"
			(at 140.335 107.95 0)
			(effects
				(font
					(size 1.27 1.27)
					(thickness 0.15)
				)
				(justify left bottom)
				(hide yes)
			)
		)
		(property "License" "Apache-2.0"
			(at 140.335 110.49 0)
			(effects
				(font
					(size 1.27 1.27)
					(thickness 0.15)
				)
				(justify left bottom)
				(hide yes)
			)
		)
		(property "Public" "False"
			(at 139.7 113.03 0)
			(effects
				(font
					(size 1.27 1.27)
				)
				(justify left bottom)
				(hide yes)
			)
		)
		(pin "1"
		)
		(instances
			(project "com-express-7-baseboard"
				(path ""
					(reference "TP14")
					(unit 1)
				)
			)
		)
	)
	(symbol
		(lib_name "R_10k_0402_1")
		(lib_id "antmicroResistors0402:R_10k_0402")
		(at 52.07 217.17 90)
		(unit 1)
		(exclude_from_sim no)
		(in_bom yes)
		(on_board yes)
		(dnp no)
		(property "Reference" "R140"
			(at 50.8 222.25 0)
			(effects
				(font
					(size 1.27 1.27)
					(thickness 0.15)
				)
				(justify left)
			)
		)
		(property "Value" "R_10k_0402"
			(at 64.77 196.85 0)
			(effects
				(font
					(size 1.27 1.27)
					(thickness 0.15)
				)
				(justify left bottom)
				(hide yes)
			)
		)
		(property "Footprint" "antmicro-footprints:R_0402_1005Metric"
			(at 67.31 196.85 0)
			(effects
				(font
					(size 1.27 1.27)
					(thickness 0.15)
				)
				(justify left bottom)
				(hide yes)
			)
		)
		(property "Datasheet" "https://www.bourns.com/docs/product-datasheets/cr.pdf"
			(at 69.85 196.85 0)
			(effects
				(font
					(size 1.27 1.27)
					(thickness 0.15)
				)
				(justify left bottom)
				(hide yes)
			)
		)
		(property "Description" "SMD Chip Resistor, 10 kohm, ± 1%, 62.5 mW, 0402 [1005 Metric], Thick Film, General Purpose"
			(at 52.07 217.17 0)
			(effects
				(font
					(size 1.27 1.27)
				)
				(hide yes)
			)
		)
		(property "MPN" "CR0402-FX-1002GLF"
			(at 72.39 196.85 0)
			(effects
				(font
					(size 1.27 1.27)
					(thickness 0.15)
				)
				(justify left bottom)
				(hide yes)
			)
		)
		(property "Manufacturer" "Bourns"
			(at 74.93 196.85 0)
			(effects
				(font
					(size 1.27 1.27)
					(thickness 0.15)
				)
				(justify left bottom)
				(hide yes)
			)
		)
		(property "License" "Apache-2.0"
			(at 77.47 196.85 0)
			(effects
				(font
					(size 1.27 1.27)
					(thickness 0.15)
				)
				(justify left bottom)
				(hide yes)
			)
		)
		(property "Author" "Antmicro"
			(at 80.01 196.85 0)
			(effects
				(font
					(size 1.27 1.27)
					(thickness 0.15)
				)
				(justify left bottom)
				(hide yes)
			)
		)
		(property "Val" "10k"
			(at 50.8 212.09 0)
			(effects
				(font
					(size 1.27 1.27)
					(thickness 0.15)
				)
				(justify left)
			)
		)
		(property "Tolerance" "1%"
			(at 62.23 196.85 0)
			(effects
				(font
					(size 1.27 1.27)
				)
				(justify left bottom)
				(hide yes)
			)
		)
		(pin "2"
		)
		(pin "1"
		)
		(instances
			(project ""
				(path ""
					(reference "R140")
					(unit 1)
				)
			)
		)
	)
	(symbol
		(lib_id "antmicropower:+3V3")
		(at 157.48 81.28 0)
		(unit 1)
		(exclude_from_sim no)
		(in_bom yes)
		(on_board yes)
		(dnp no)
		(property "Reference" "#PWR0199"
			(at 172.72 81.28 0)
			(effects
				(font
					(size 1.27 1.27)
					(thickness 0.15)
				)
				(justify left bottom)
				(hide yes)
			)
		)
		(property "Value" "+3V3"
			(at 157.48 77.47 0)
			(effects
				(font
					(size 1.27 1.27)
					(thickness 0.15)
				)
			)
		)
		(property "Footprint" ""
			(at 172.72 88.9 0)
			(effects
				(font
					(size 1.27 1.27)
					(thickness 0.15)
				)
				(justify left bottom)
				(hide yes)
			)
		)
		(property "Datasheet" ""
			(at 172.72 91.44 0)
			(effects
				(font
					(size 1.27 1.27)
					(thickness 0.15)
				)
				(justify left bottom)
				(hide yes)
			)
		)
		(property "Description" ""
			(at 157.48 81.28 0)
			(effects
				(font
					(size 1.27 1.27)
				)
				(hide yes)
			)
		)
		(property "Author" "Antmicro"
			(at 172.72 83.82 0)
			(effects
				(font
					(size 1.27 1.27)
					(thickness 0.15)
				)
				(justify left bottom)
				(hide yes)
			)
		)
		(property "License" "Apache-2.0"
			(at 172.72 86.36 0)
			(effects
				(font
					(size 1.27 1.27)
					(thickness 0.15)
				)
				(justify left bottom)
				(hide yes)
			)
		)
		(pin "1"
		)
		(instances
			(project "com-express-7-baseboard"
				(path ""
					(reference "#PWR0199")
					(unit 1)
				)
			)
		)
	)
	(symbol
		(lib_id "antmicroResistors0402:R_0R_0402")
		(at 82.55 73.66 0)
		(unit 1)
		(exclude_from_sim no)
		(in_bom yes)
		(on_board yes)
		(dnp no)
		(property "Reference" "R149"
			(at 80.01 72.39 0)
			(effects
				(font
					(size 1.27 1.27)
					(thickness 0.15)
				)
			)
		)
		(property "Value" "R_0R_0402"
			(at 102.87 86.36 0)
			(effects
				(font
					(size 1.27 1.27)
					(thickness 0.15)
				)
				(justify left bottom)
				(hide yes)
			)
		)
		(property "Footprint" "antmicro-footprints:R_0402_1005Metric"
			(at 102.87 88.9 0)
			(effects
				(font
					(size 1.27 1.27)
					(thickness 0.15)
				)
				(justify left bottom)
				(hide yes)
			)
		)
		(property "Datasheet" "https://industrial.panasonic.com/cdbs/www-data/pdf/RDA0000/AOA0000C301.pdf"
			(at 102.87 91.44 0)
			(effects
				(font
					(size 1.27 1.27)
					(thickness 0.15)
				)
				(justify left bottom)
				(hide yes)
			)
		)
		(property "Description" ""
			(at 82.55 73.66 0)
			(effects
				(font
					(size 1.27 1.27)
				)
				(hide yes)
			)
		)
		(property "MPN" "ERJ2GE0R00X"
			(at 102.87 93.98 0)
			(effects
				(font
					(size 1.27 1.27)
					(thickness 0.15)
				)
				(justify left bottom)
				(hide yes)
			)
		)
		(property "Manufacturer" "Panasonic"
			(at 102.87 96.52 0)
			(effects
				(font
					(size 1.27 1.27)
					(thickness 0.15)
				)
				(justify left bottom)
				(hide yes)
			)
		)
		(property "License" "Apache-2.0"
			(at 102.87 99.06 0)
			(effects
				(font
					(size 1.27 1.27)
					(thickness 0.15)
				)
				(justify left bottom)
				(hide yes)
			)
		)
		(property "Author" "Antmicro"
			(at 102.87 101.6 0)
			(effects
				(font
					(size 1.27 1.27)
					(thickness 0.15)
				)
				(justify left bottom)
				(hide yes)
			)
		)
		(property "Val" "0R"
			(at 88.9 72.39 0)
			(effects
				(font
					(size 1.27 1.27)
					(thickness 0.15)
				)
			)
		)
		(property "Tolerance" "~"
			(at 102.87 83.82 0)
			(effects
				(font
					(size 1.27 1.27)
				)
				(justify left bottom)
				(hide yes)
			)
		)
		(property "Current" "1A"
			(at 102.87 104.14 0)
			(effects
				(font
					(size 1.27 1.27)
					(thickness 0.15)
				)
				(justify left bottom)
				(hide yes)
			)
		)
		(property "Public" "False"
			(at 102.87 104.14 0)
			(effects
				(font
					(size 1.27 1.27)
				)
				(justify left bottom)
				(hide yes)
			)
		)
		(pin "2"
		)
		(pin "1"
		)
		(instances
			(project "com-express-7-baseboard"
				(path ""
					(reference "R149")
					(unit 1)
				)
			)
		)
	)
	(symbol
		(lib_id "antmicropower:GND")
		(at 349.25 107.95 0)
		(unit 1)
		(exclude_from_sim no)
		(in_bom yes)
		(on_board yes)
		(dnp no)
		(property "Reference" "#PWR0220"
			(at 358.14 110.49 0)
			(effects
				(font
					(size 1.27 1.27)
					(thickness 0.15)
				)
				(justify left bottom)
				(hide yes)
			)
		)
		(property "Value" "GND"
			(at 349.25 111.76 0)
			(effects
				(font
					(size 1.27 1.27)
					(thickness 0.15)
				)
			)
		)
		(property "Footprint" ""
			(at 358.14 115.57 0)
			(effects
				(font
					(size 1.27 1.27)
					(thickness 0.15)
				)
				(justify left bottom)
				(hide yes)
			)
		)
		(property "Datasheet" ""
			(at 358.14 120.65 0)
			(effects
				(font
					(size 1.27 1.27)
					(thickness 0.15)
				)
				(justify left bottom)
				(hide yes)
			)
		)
		(property "Description" ""
			(at 349.25 107.95 0)
			(effects
				(font
					(size 1.27 1.27)
				)
				(hide yes)
			)
		)
		(property "Author" "Antmicro"
			(at 358.14 115.57 0)
			(effects
				(font
					(size 1.27 1.27)
					(thickness 0.15)
				)
				(justify left bottom)
				(hide yes)
			)
		)
		(property "License" "Apache-2.0"
			(at 358.14 118.11 0)
			(effects
				(font
					(size 1.27 1.27)
					(thickness 0.15)
				)
				(justify left bottom)
				(hide yes)
			)
		)
		(pin "1"
		)
		(instances
			(project "com-express-7-baseboard"
				(path ""
					(reference "#PWR0220")
					(unit 1)
				)
			)
		)
	)
	(symbol
		(lib_id "antmicroCapacitors0402:C_100n_0402")
		(at 271.78 171.45 270)
		(mirror x)
		(unit 1)
		(exclude_from_sim no)
		(in_bom yes)
		(on_board yes)
		(dnp no)
		(property "Reference" "C85"
			(at 271.145 167.005 90)
			(effects
				(font
					(size 1.27 1.27)
					(thickness 0.15)
				)
				(justify right)
			)
		)
		(property "Value" "C_100n_0402"
			(at 261.62 151.13 0)
			(effects
				(font
					(size 1.27 1.27)
					(thickness 0.15)
				)
				(justify left bottom)
				(hide yes)
			)
		)
		(property "Footprint" "antmicro-footprints:C_0402_1005Metric"
			(at 259.08 151.13 0)
			(effects
				(font
					(size 1.27 1.27)
					(thickness 0.15)
				)
				(justify left bottom)
				(hide yes)
			)
		)
		(property "Datasheet" "https://www.murata.com/products/productdetail?partno=GRM155R61H104KE14%23"
			(at 256.54 151.13 0)
			(effects
				(font
					(size 1.27 1.27)
					(thickness 0.15)
				)
				(justify left bottom)
				(hide yes)
			)
		)
		(property "Description" ""
			(at 271.78 171.45 0)
			(effects
				(font
					(size 1.27 1.27)
				)
				(hide yes)
			)
		)
		(property "MPN" "GRM155R61H104KE14D"
			(at 254 151.13 0)
			(effects
				(font
					(size 1.27 1.27)
					(thickness 0.15)
				)
				(justify left bottom)
				(hide yes)
			)
		)
		(property "Manufacturer" "Murata"
			(at 251.46 151.13 0)
			(effects
				(font
					(size 1.27 1.27)
					(thickness 0.15)
				)
				(justify left bottom)
				(hide yes)
			)
		)
		(property "License" "Apache-2.0"
			(at 248.92 151.13 0)
			(effects
				(font
					(size 1.27 1.27)
					(thickness 0.15)
				)
				(justify left bottom)
				(hide yes)
			)
		)
		(property "Author" "Antmicro"
			(at 246.38 151.13 0)
			(effects
				(font
					(size 1.27 1.27)
					(thickness 0.15)
				)
				(justify left bottom)
				(hide yes)
			)
		)
		(property "Val" "100n"
			(at 271.145 170.815 90)
			(effects
				(font
					(size 1.27 1.27)
					(thickness 0.15)
				)
				(justify right)
			)
		)
		(property "Voltage" "50V"
			(at 243.84 151.13 0)
			(effects
				(font
					(size 1.27 1.27)
				)
				(justify left bottom)
				(hide yes)
			)
		)
		(property "Dielectric" "X5R"
			(at 241.3 151.13 0)
			(effects
				(font
					(size 1.27 1.27)
				)
				(justify left bottom)
				(hide yes)
			)
		)
		(property "Public" "False"
			(at 238.76 151.13 0)
			(effects
				(font
					(size 1.27 1.27)
				)
				(justify left bottom)
				(hide yes)
			)
		)
		(pin "2"
		)
		(pin "1"
		)
		(instances
			(project "com-express-7-baseboard"
				(path ""
					(reference "C85")
					(unit 1)
				)
			)
		)
	)
	(symbol
		(lib_id "antmicroTransistorsFETsMOSFETsSingle:BSS138-7-F")
		(at 90.17 233.68 0)
		(unit 1)
		(exclude_from_sim no)
		(in_bom yes)
		(on_board yes)
		(dnp no)
		(property "Reference" "Q7"
			(at 101.6 229.8699 0)
			(effects
				(font
					(size 1.27 1.27)
					(thickness 0.15)
				)
				(justify left)
			)
		)
		(property "Value" "BSS138-7-F"
			(at 101.6 232.4099 0)
			(effects
				(font
					(size 1.27 1.27)
					(thickness 0.15)
				)
				(justify left)
				(hide yes)
			)
		)
		(property "Footprint" "antmicro-footprints:SOT-23-3"
			(at 113.03 241.3 0)
			(effects
				(font
					(size 1.27 1.27)
					(thickness 0.15)
				)
				(justify left bottom)
				(hide yes)
			)
		)
		(property "Datasheet" "https://www.diodes.com/assets/Datasheets/ds30144.pdf"
			(at 113.03 243.84 0)
			(effects
				(font
					(size 1.27 1.27)
					(thickness 0.15)
				)
				(justify left bottom)
				(hide yes)
			)
		)
		(property "Description" ""
			(at 90.17 233.68 0)
			(effects
				(font
					(size 1.27 1.27)
				)
				(hide yes)
			)
		)
		(property "MPN" "BSS138-7-F"
			(at 101.6 233.68 0)
			(effects
				(font
					(size 1.27 1.27)
					(thickness 0.15)
				)
				(justify left bottom)
			)
		)
		(property "Manufacturer" "Diodes Incorporated"
			(at 113.03 248.92 0)
			(effects
				(font
					(size 1.27 1.27)
					(thickness 0.15)
				)
				(justify left bottom)
				(hide yes)
			)
		)
		(property "Author" "Antmicro"
			(at 113.03 251.46 0)
			(effects
				(font
					(size 1.27 1.27)
					(thickness 0.15)
				)
				(justify left bottom)
				(hide yes)
			)
		)
		(property "License" "Apache-2.0"
			(at 113.03 254 0)
			(effects
				(font
					(size 1.27 1.27)
					(thickness 0.15)
				)
				(justify left bottom)
				(hide yes)
			)
		)
		(pin "1"
		)
		(pin "3"
		)
		(pin "2"
		)
		(instances
			(project "com-express-7-baseboard"
				(path ""
					(reference "Q7")
					(unit 1)
				)
			)
		)
	)
	(symbol
		(lib_id "antmicroTransistorsBipolarSingle:MMBT3904LT1G")
		(at 162.56 119.38 0)
		(unit 1)
		(exclude_from_sim no)
		(in_bom yes)
		(on_board yes)
		(dnp no)
		(fields_autoplaced yes)
		(property "Reference" "Q10"
			(at 171.45 118.11 0)
			(effects
				(font
					(size 1.27 1.27)
					(thickness 0.15)
				)
				(justify left)
			)
		)
		(property "Value" "MMBT3904LT1G"
			(at 177.8 129.54 0)
			(effects
				(font
					(size 1.27 1.27)
					(thickness 0.15)
				)
				(justify left bottom)
				(hide yes)
			)
		)
		(property "Footprint" "antmicro-footprints:SOT-23-3"
			(at 177.8 132.08 0)
			(effects
				(font
					(size 1.27 1.27)
					(thickness 0.15)
				)
				(justify left bottom)
				(hide yes)
			)
		)
		(property "Datasheet" "https://eu.mouser.com/datasheet/2/308/1/MMBT3904LT1_D-2316262.pdf"
			(at 177.8 134.62 0)
			(effects
				(font
					(size 1.27 1.27)
					(thickness 0.15)
				)
				(justify left bottom)
				(hide yes)
			)
		)
		(property "Description" ""
			(at 162.56 119.38 0)
			(effects
				(font
					(size 1.27 1.27)
				)
				(hide yes)
			)
		)
		(property "MPN" "MMBT3904LT1G"
			(at 171.45 120.65 0)
			(effects
				(font
					(size 1.27 1.27)
					(thickness 0.15)
				)
				(justify left)
			)
		)
		(property "Manufacturer" "Onsemi"
			(at 177.8 137.16 0)
			(effects
				(font
					(size 1.27 1.27)
					(thickness 0.15)
				)
				(justify left bottom)
				(hide yes)
			)
		)
		(property "Author" "Antmicro"
			(at 177.8 139.7 0)
			(effects
				(font
					(size 1.27 1.27)
					(thickness 0.15)
				)
				(justify left bottom)
				(hide yes)
			)
		)
		(property "License" "Apache-2.0"
			(at 177.8 142.24 0)
			(effects
				(font
					(size 1.27 1.27)
					(thickness 0.15)
				)
				(justify left bottom)
				(hide yes)
			)
		)
		(property "Public" "False"
			(at 185.42 139.7 0)
			(effects
				(font
					(size 1.27 1.27)
				)
				(justify left bottom)
				(hide yes)
			)
		)
		(pin "2"
		)
		(pin "1"
		)
		(pin "3"
		)
		(instances
			(project "com-express-7-baseboard"
				(path ""
					(reference "Q10")
					(unit 1)
				)
			)
		)
	)
	(symbol
		(lib_id "antmicroLogicTranslatorsLevelShifters:NTS0102_TSSOP")
		(at 311.15 154.94 0)
		(unit 1)
		(exclude_from_sim no)
		(in_bom yes)
		(on_board yes)
		(dnp no)
		(property "Reference" "U28"
			(at 321.31 148.59 0)
			(effects
				(font
					(size 1.27 1.27)
					(thickness 0.15)
				)
			)
		)
		(property "Value" "NTS0102_TSSOP"
			(at 321.31 149.86 0)
			(effects
				(font
					(size 1.27 1.27)
					(thickness 0.15)
				)
				(hide yes)
			)
		)
		(property "Footprint" "antmicro-footprints:TSSOP-8_3x3mm_P0.65mm"
			(at 346.71 163.83 0)
			(effects
				(font
					(size 1.27 1.27)
					(thickness 0.15)
				)
				(justify left bottom)
				(hide yes)
			)
		)
		(property "Datasheet" "https://www.mouser.com/datasheet/2/302/NTS0102-1127324.pdf"
			(at 346.71 166.37 0)
			(effects
				(font
					(size 1.27 1.27)
					(thickness 0.15)
				)
				(justify left bottom)
				(hide yes)
			)
		)
		(property "Description" ""
			(at 311.15 154.94 0)
			(effects
				(font
					(size 1.27 1.27)
				)
				(hide yes)
			)
		)
		(property "MPN" "NTS0102DP"
			(at 316.23 151.13 0)
			(effects
				(font
					(size 1.27 1.27)
					(thickness 0.15)
				)
				(justify left bottom)
			)
		)
		(property "Manufacturer" "NXP"
			(at 346.71 171.45 0)
			(effects
				(font
					(size 1.27 1.27)
					(thickness 0.15)
				)
				(justify left bottom)
				(hide yes)
			)
		)
		(property "Author" "Antmicro"
			(at 346.71 173.99 0)
			(effects
				(font
					(size 1.27 1.27)
					(thickness 0.15)
				)
				(justify left bottom)
				(hide yes)
			)
		)
		(property "License" "Apache-2.0"
			(at 346.71 176.53 0)
			(effects
				(font
					(size 1.27 1.27)
					(thickness 0.15)
				)
				(justify left bottom)
				(hide yes)
			)
		)
		(pin "3"
		)
		(pin "6"
		)
		(pin "7"
		)
		(pin "4"
		)
		(pin "5"
		)
		(pin "2"
		)
		(pin "1"
		)
		(pin "8"
		)
		(instances
			(project "com-express-7-baseboard"
				(path ""
					(reference "U28")
					(unit 1)
				)
			)
		)
	)
	(symbol
		(lib_name "R_10k_0402_1")
		(lib_id "antmicroResistors0402:R_10k_0402")
		(at 97.79 217.17 90)
		(unit 1)
		(exclude_from_sim no)
		(in_bom yes)
		(on_board yes)
		(dnp no)
		(property "Reference" "R152"
			(at 96.52 222.25 0)
			(effects
				(font
					(size 1.27 1.27)
					(thickness 0.15)
				)
				(justify left)
			)
		)
		(property "Value" "R_10k_0402"
			(at 110.49 196.85 0)
			(effects
				(font
					(size 1.27 1.27)
					(thickness 0.15)
				)
				(justify left bottom)
				(hide yes)
			)
		)
		(property "Footprint" "antmicro-footprints:R_0402_1005Metric"
			(at 113.03 196.85 0)
			(effects
				(font
					(size 1.27 1.27)
					(thickness 0.15)
				)
				(justify left bottom)
				(hide yes)
			)
		)
		(property "Datasheet" "https://www.bourns.com/docs/product-datasheets/cr.pdf"
			(at 115.57 196.85 0)
			(effects
				(font
					(size 1.27 1.27)
					(thickness 0.15)
				)
				(justify left bottom)
				(hide yes)
			)
		)
		(property "Description" "SMD Chip Resistor, 10 kohm, ± 1%, 62.5 mW, 0402 [1005 Metric], Thick Film, General Purpose"
			(at 97.79 217.17 0)
			(effects
				(font
					(size 1.27 1.27)
				)
				(hide yes)
			)
		)
		(property "MPN" "CR0402-FX-1002GLF"
			(at 118.11 196.85 0)
			(effects
				(font
					(size 1.27 1.27)
					(thickness 0.15)
				)
				(justify left bottom)
				(hide yes)
			)
		)
		(property "Manufacturer" "Bourns"
			(at 120.65 196.85 0)
			(effects
				(font
					(size 1.27 1.27)
					(thickness 0.15)
				)
				(justify left bottom)
				(hide yes)
			)
		)
		(property "License" "Apache-2.0"
			(at 123.19 196.85 0)
			(effects
				(font
					(size 1.27 1.27)
					(thickness 0.15)
				)
				(justify left bottom)
				(hide yes)
			)
		)
		(property "Author" "Antmicro"
			(at 125.73 196.85 0)
			(effects
				(font
					(size 1.27 1.27)
					(thickness 0.15)
				)
				(justify left bottom)
				(hide yes)
			)
		)
		(property "Val" "10k"
			(at 96.52 212.09 0)
			(effects
				(font
					(size 1.27 1.27)
					(thickness 0.15)
				)
				(justify left)
			)
		)
		(property "Tolerance" "1%"
			(at 107.95 196.85 0)
			(effects
				(font
					(size 1.27 1.27)
				)
				(justify left bottom)
				(hide yes)
			)
		)
		(pin "2"
		)
		(pin "1"
		)
		(instances
			(project "com-express-7-baseboard"
				(path ""
					(reference "R152")
					(unit 1)
				)
			)
		)
	)
	(symbol
		(lib_id "antmicropower:GND")
		(at 344.17 90.17 0)
		(unit 1)
		(exclude_from_sim no)
		(in_bom yes)
		(on_board yes)
		(dnp no)
		(property "Reference" "#PWR0213"
			(at 353.06 92.71 0)
			(effects
				(font
					(size 1.27 1.27)
					(thickness 0.15)
				)
				(justify left bottom)
				(hide yes)
			)
		)
		(property "Value" "GND"
			(at 344.17 93.98 0)
			(effects
				(font
					(size 1.27 1.27)
					(thickness 0.15)
				)
			)
		)
		(property "Footprint" ""
			(at 353.06 97.79 0)
			(effects
				(font
					(size 1.27 1.27)
					(thickness 0.15)
				)
				(justify left bottom)
				(hide yes)
			)
		)
		(property "Datasheet" ""
			(at 353.06 102.87 0)
			(effects
				(font
					(size 1.27 1.27)
					(thickness 0.15)
				)
				(justify left bottom)
				(hide yes)
			)
		)
		(property "Description" ""
			(at 344.17 90.17 0)
			(effects
				(font
					(size 1.27 1.27)
				)
				(hide yes)
			)
		)
		(property "Author" "Antmicro"
			(at 353.06 97.79 0)
			(effects
				(font
					(size 1.27 1.27)
					(thickness 0.15)
				)
				(justify left bottom)
				(hide yes)
			)
		)
		(property "License" "Apache-2.0"
			(at 353.06 100.33 0)
			(effects
				(font
					(size 1.27 1.27)
					(thickness 0.15)
				)
				(justify left bottom)
				(hide yes)
			)
		)
		(pin "1"
		)
		(instances
			(project "com-express-7-baseboard"
				(path ""
					(reference "#PWR0213")
					(unit 1)
				)
			)
		)
	)
	(symbol
		(lib_id "antmicropower:GND")
		(at 307.34 214.63 0)
		(mirror y)
		(unit 1)
		(exclude_from_sim no)
		(in_bom yes)
		(on_board yes)
		(dnp no)
		(property "Reference" "#PWR0212"
			(at 298.45 217.17 0)
			(effects
				(font
					(size 1.27 1.27)
					(thickness 0.15)
				)
				(justify left bottom)
				(hide yes)
			)
		)
		(property "Value" "GND"
			(at 307.34 218.44 0)
			(effects
				(font
					(size 1.27 1.27)
					(thickness 0.15)
				)
			)
		)
		(property "Footprint" ""
			(at 298.45 222.25 0)
			(effects
				(font
					(size 1.27 1.27)
					(thickness 0.15)
				)
				(justify left bottom)
				(hide yes)
			)
		)
		(property "Datasheet" ""
			(at 298.45 227.33 0)
			(effects
				(font
					(size 1.27 1.27)
					(thickness 0.15)
				)
				(justify left bottom)
				(hide yes)
			)
		)
		(property "Description" ""
			(at 307.34 214.63 0)
			(effects
				(font
					(size 1.27 1.27)
				)
				(hide yes)
			)
		)
		(property "Author" "Antmicro"
			(at 298.45 222.25 0)
			(effects
				(font
					(size 1.27 1.27)
					(thickness 0.15)
				)
				(justify left bottom)
				(hide yes)
			)
		)
		(property "License" "Apache-2.0"
			(at 298.45 224.79 0)
			(effects
				(font
					(size 1.27 1.27)
					(thickness 0.15)
				)
				(justify left bottom)
				(hide yes)
			)
		)
		(pin "1"
		)
		(instances
			(project "com-express-7-baseboard"
				(path ""
					(reference "#PWR0212")
					(unit 1)
				)
			)
		)
	)
	(symbol
		(lib_id "antmicroResistors0402:R_0R_0402")
		(at 82.55 78.74 0)
		(unit 1)
		(exclude_from_sim no)
		(in_bom yes)
		(on_board yes)
		(dnp no)
		(property "Reference" "R151"
			(at 80.01 77.47 0)
			(effects
				(font
					(size 1.27 1.27)
					(thickness 0.15)
				)
			)
		)
		(property "Value" "R_0R_0402"
			(at 102.87 91.44 0)
			(effects
				(font
					(size 1.27 1.27)
					(thickness 0.15)
				)
				(justify left bottom)
				(hide yes)
			)
		)
		(property "Footprint" "antmicro-footprints:R_0402_1005Metric"
			(at 102.87 93.98 0)
			(effects
				(font
					(size 1.27 1.27)
					(thickness 0.15)
				)
				(justify left bottom)
				(hide yes)
			)
		)
		(property "Datasheet" "https://industrial.panasonic.com/cdbs/www-data/pdf/RDA0000/AOA0000C301.pdf"
			(at 102.87 96.52 0)
			(effects
				(font
					(size 1.27 1.27)
					(thickness 0.15)
				)
				(justify left bottom)
				(hide yes)
			)
		)
		(property "Description" ""
			(at 82.55 78.74 0)
			(effects
				(font
					(size 1.27 1.27)
				)
				(hide yes)
			)
		)
		(property "MPN" "ERJ2GE0R00X"
			(at 102.87 99.06 0)
			(effects
				(font
					(size 1.27 1.27)
					(thickness 0.15)
				)
				(justify left bottom)
				(hide yes)
			)
		)
		(property "Manufacturer" "Panasonic"
			(at 102.87 101.6 0)
			(effects
				(font
					(size 1.27 1.27)
					(thickness 0.15)
				)
				(justify left bottom)
				(hide yes)
			)
		)
		(property "License" "Apache-2.0"
			(at 102.87 104.14 0)
			(effects
				(font
					(size 1.27 1.27)
					(thickness 0.15)
				)
				(justify left bottom)
				(hide yes)
			)
		)
		(property "Author" "Antmicro"
			(at 102.87 106.68 0)
			(effects
				(font
					(size 1.27 1.27)
					(thickness 0.15)
				)
				(justify left bottom)
				(hide yes)
			)
		)
		(property "Val" "0R"
			(at 88.9 77.47 0)
			(effects
				(font
					(size 1.27 1.27)
					(thickness 0.15)
				)
			)
		)
		(property "Tolerance" "~"
			(at 102.87 88.9 0)
			(effects
				(font
					(size 1.27 1.27)
				)
				(justify left bottom)
				(hide yes)
			)
		)
		(property "Current" "1A"
			(at 102.87 109.22 0)
			(effects
				(font
					(size 1.27 1.27)
					(thickness 0.15)
				)
				(justify left bottom)
				(hide yes)
			)
		)
		(property "Public" "False"
			(at 102.87 109.22 0)
			(effects
				(font
					(size 1.27 1.27)
				)
				(justify left bottom)
				(hide yes)
			)
		)
		(pin "2"
		)
		(pin "1"
		)
		(instances
			(project "com-express-7-baseboard"
				(path ""
					(reference "R151")
					(unit 1)
				)
			)
		)
	)
	(symbol
		(lib_id "antmicroTestPoints:TP_0.75mm_SMD")
		(at 129.54 96.52 0)
		(unit 1)
		(exclude_from_sim no)
		(in_bom no)
		(on_board yes)
		(dnp no)
		(fields_autoplaced yes)
		(property "Reference" "TP13"
			(at 134.62 96.52 0)
			(effects
				(font
					(size 1.27 1.27)
					(thickness 0.15)
				)
				(justify left)
			)
		)
		(property "Value" "TP_0.75mm_SMD"
			(at 140.335 100.33 0)
			(effects
				(font
					(size 1.27 1.27)
					(thickness 0.15)
				)
				(justify left bottom)
				(hide yes)
			)
		)
		(property "Footprint" "antmicro-footprints:TP_SMD_0.75mm"
			(at 140.335 102.87 0)
			(effects
				(font
					(size 1.27 1.27)
					(thickness 0.15)
				)
				(justify left bottom)
				(hide yes)
			)
		)
		(property "Datasheet" ""
			(at 147.32 109.22 0)
			(effects
				(font
					(size 1.27 1.27)
					(thickness 0.15)
				)
				(justify left bottom)
				(hide yes)
			)
		)
		(property "Description" ""
			(at 129.54 96.52 0)
			(effects
				(font
					(size 1.27 1.27)
				)
				(hide yes)
			)
		)
		(property "MPN" ""
			(at 140.335 107.95 0)
			(effects
				(font
					(size 1.27 1.27)
					(thickness 0.15)
				)
				(justify left bottom)
				(hide yes)
			)
		)
		(property "Manufacturer" ""
			(at 140.335 102.87 0)
			(effects
				(font
					(size 1.27 1.27)
					(thickness 0.15)
				)
				(justify left bottom)
				(hide yes)
			)
		)
		(property "Author" "Antmicro"
			(at 140.335 105.41 0)
			(effects
				(font
					(size 1.27 1.27)
					(thickness 0.15)
				)
				(justify left bottom)
				(hide yes)
			)
		)
		(property "License" "Apache-2.0"
			(at 140.335 107.95 0)
			(effects
				(font
					(size 1.27 1.27)
					(thickness 0.15)
				)
				(justify left bottom)
				(hide yes)
			)
		)
		(property "Public" "False"
			(at 139.7 110.49 0)
			(effects
				(font
					(size 1.27 1.27)
				)
				(justify left bottom)
				(hide yes)
			)
		)
		(pin "1"
		)
		(instances
			(project "com-express-7-baseboard"
				(path ""
					(reference "TP13")
					(unit 1)
				)
			)
		)
	)
	(symbol
		(lib_id "antmicroCapacitors0402:C_100n_0402")
		(at 335.28 154.94 90)
		(unit 1)
		(exclude_from_sim no)
		(in_bom yes)
		(on_board yes)
		(dnp no)
		(fields_autoplaced yes)
		(property "Reference" "C91"
			(at 337.82 151.1236 90)
			(effects
				(font
					(size 1.27 1.27)
					(thickness 0.15)
				)
				(justify right)
			)
		)
		(property "Value" "C_100n_0402"
			(at 345.44 134.62 0)
			(effects
				(font
					(size 1.27 1.27)
					(thickness 0.15)
				)
				(justify left bottom)
				(hide yes)
			)
		)
		(property "Footprint" "antmicro-footprints:C_0402_1005Metric"
			(at 347.98 134.62 0)
			(effects
				(font
					(size 1.27 1.27)
					(thickness 0.15)
				)
				(justify left bottom)
				(hide yes)
			)
		)
		(property "Datasheet" "https://www.murata.com/products/productdetail?partno=GRM155R61H104KE14%23"
			(at 350.52 134.62 0)
			(effects
				(font
					(size 1.27 1.27)
					(thickness 0.15)
				)
				(justify left bottom)
				(hide yes)
			)
		)
		(property "Description" ""
			(at 335.28 154.94 0)
			(effects
				(font
					(size 1.27 1.27)
				)
				(hide yes)
			)
		)
		(property "MPN" "GRM155R61H104KE14D"
			(at 353.06 134.62 0)
			(effects
				(font
					(size 1.27 1.27)
					(thickness 0.15)
				)
				(justify left bottom)
				(hide yes)
			)
		)
		(property "Manufacturer" "Murata"
			(at 355.6 134.62 0)
			(effects
				(font
					(size 1.27 1.27)
					(thickness 0.15)
				)
				(justify left bottom)
				(hide yes)
			)
		)
		(property "License" "Apache-2.0"
			(at 358.14 134.62 0)
			(effects
				(font
					(size 1.27 1.27)
					(thickness 0.15)
				)
				(justify left bottom)
				(hide yes)
			)
		)
		(property "Author" "Antmicro"
			(at 360.68 134.62 0)
			(effects
				(font
					(size 1.27 1.27)
					(thickness 0.15)
				)
				(justify left bottom)
				(hide yes)
			)
		)
		(property "Val" "100n"
			(at 337.82 153.6636 90)
			(effects
				(font
					(size 1.27 1.27)
					(thickness 0.15)
				)
				(justify right)
			)
		)
		(property "Voltage" "50V"
			(at 363.22 134.62 0)
			(effects
				(font
					(size 1.27 1.27)
				)
				(justify left bottom)
				(hide yes)
			)
		)
		(property "Dielectric" "X5R"
			(at 365.76 134.62 0)
			(effects
				(font
					(size 1.27 1.27)
				)
				(justify left bottom)
				(hide yes)
			)
		)
		(property "Public" "False"
			(at 368.3 134.62 0)
			(effects
				(font
					(size 1.27 1.27)
				)
				(justify left bottom)
				(hide yes)
			)
		)
		(pin "2"
		)
		(pin "1"
		)
		(instances
			(project "com-express-7-baseboard"
				(path ""
					(reference "C91")
					(unit 1)
				)
			)
		)
	)
	(symbol
		(lib_id "antmicroCapacitors0603:C_22u_16V_0603")
		(at 344.17 90.17 90)
		(unit 1)
		(exclude_from_sim no)
		(in_bom yes)
		(on_board yes)
		(dnp no)
		(fields_autoplaced yes)
		(property "Reference" "C89"
			(at 346.71 85.0835 90)
			(effects
				(font
					(size 1.27 1.27)
					(thickness 0.15)
				)
				(justify right)
			)
		)
		(property "Value" "C_22u_16V_0603"
			(at 354.33 69.85 0)
			(effects
				(font
					(size 1.27 1.27)
					(thickness 0.15)
				)
				(justify left bottom)
				(hide yes)
			)
		)
		(property "Footprint" "antmicro-footprints:C_0603_1608Metric"
			(at 356.87 69.85 0)
			(effects
				(font
					(size 1.27 1.27)
					(thickness 0.15)
				)
				(justify left bottom)
				(hide yes)
			)
		)
		(property "Datasheet" "https://product.samsungsem.com/mlcc/CL10A226MO7JZN.do"
			(at 359.41 69.85 0)
			(effects
				(font
					(size 1.27 1.27)
					(thickness 0.15)
				)
				(justify left bottom)
				(hide yes)
			)
		)
		(property "Description" ""
			(at 344.17 90.17 0)
			(effects
				(font
					(size 1.27 1.27)
				)
				(hide yes)
			)
		)
		(property "MPN" "CL10A226MO7JZNC"
			(at 361.95 69.85 0)
			(effects
				(font
					(size 1.27 1.27)
					(thickness 0.15)
				)
				(justify left bottom)
				(hide yes)
			)
		)
		(property "Manufacturer" "Samsung Electro-Mechanics"
			(at 364.49 69.85 0)
			(effects
				(font
					(size 1.27 1.27)
					(thickness 0.15)
				)
				(justify left bottom)
				(hide yes)
			)
		)
		(property "License" "Apache-2.0"
			(at 367.03 69.85 0)
			(effects
				(font
					(size 1.27 1.27)
					(thickness 0.15)
				)
				(justify left bottom)
				(hide yes)
			)
		)
		(property "Author" "Antmicro"
			(at 369.57 69.85 0)
			(effects
				(font
					(size 1.27 1.27)
					(thickness 0.15)
				)
				(justify left bottom)
				(hide yes)
			)
		)
		(property "Val" "22u"
			(at 346.71 87.6235 90)
			(effects
				(font
					(size 1.27 1.27)
					(thickness 0.15)
				)
				(justify right)
			)
		)
		(property "Voltage" "16V"
			(at 346.71 90.1635 90)
			(effects
				(font
					(size 1.27 1.27)
				)
				(justify right)
				(hide yes)
			)
		)
		(property "Dielectric" ""
			(at 374.65 69.85 0)
			(effects
				(font
					(size 1.27 1.27)
				)
				(justify left bottom)
				(hide yes)
			)
		)
		(property "Public" "False"
			(at 377.19 69.85 0)
			(effects
				(font
					(size 1.27 1.27)
				)
				(justify left bottom)
				(hide yes)
			)
		)
		(pin "2"
		)
		(pin "1"
		)
		(instances
			(project "com-express-7-baseboard"
				(path ""
					(reference "C89")
					(unit 1)
				)
			)
		)
	)
	(symbol
		(lib_id "antmicroCapacitors0603:C_22u_16V_0603")
		(at 344.17 196.85 90)
		(unit 1)
		(exclude_from_sim no)
		(in_bom yes)
		(on_board yes)
		(dnp no)
		(fields_autoplaced yes)
		(property "Reference" "C7"
			(at 346.71 191.7635 90)
			(effects
				(font
					(size 1.27 1.27)
					(thickness 0.15)
				)
				(justify right)
			)
		)
		(property "Value" "C_22u_16V_0603"
			(at 354.33 176.53 0)
			(effects
				(font
					(size 1.27 1.27)
					(thickness 0.15)
				)
				(justify left bottom)
				(hide yes)
			)
		)
		(property "Footprint" "antmicro-footprints:C_0603_1608Metric"
			(at 356.87 176.53 0)
			(effects
				(font
					(size 1.27 1.27)
					(thickness 0.15)
				)
				(justify left bottom)
				(hide yes)
			)
		)
		(property "Datasheet" "https://product.samsungsem.com/mlcc/CL10A226MO7JZN.do"
			(at 359.41 176.53 0)
			(effects
				(font
					(size 1.27 1.27)
					(thickness 0.15)
				)
				(justify left bottom)
				(hide yes)
			)
		)
		(property "Description" ""
			(at 344.17 196.85 0)
			(effects
				(font
					(size 1.27 1.27)
				)
				(hide yes)
			)
		)
		(property "MPN" "CL10A226MO7JZNC"
			(at 361.95 176.53 0)
			(effects
				(font
					(size 1.27 1.27)
					(thickness 0.15)
				)
				(justify left bottom)
				(hide yes)
			)
		)
		(property "Manufacturer" "Samsung Electro-Mechanics"
			(at 364.49 176.53 0)
			(effects
				(font
					(size 1.27 1.27)
					(thickness 0.15)
				)
				(justify left bottom)
				(hide yes)
			)
		)
		(property "License" "Apache-2.0"
			(at 367.03 176.53 0)
			(effects
				(font
					(size 1.27 1.27)
					(thickness 0.15)
				)
				(justify left bottom)
				(hide yes)
			)
		)
		(property "Author" "Antmicro"
			(at 369.57 176.53 0)
			(effects
				(font
					(size 1.27 1.27)
					(thickness 0.15)
				)
				(justify left bottom)
				(hide yes)
			)
		)
		(property "Val" "22u"
			(at 346.71 194.3035 90)
			(effects
				(font
					(size 1.27 1.27)
					(thickness 0.15)
				)
				(justify right)
			)
		)
		(property "Voltage" "16V"
			(at 346.71 196.8435 90)
			(effects
				(font
					(size 1.27 1.27)
				)
				(justify right)
				(hide yes)
			)
		)
		(property "Dielectric" ""
			(at 374.65 176.53 0)
			(effects
				(font
					(size 1.27 1.27)
				)
				(justify left bottom)
				(hide yes)
			)
		)
		(property "Public" "False"
			(at 377.19 176.53 0)
			(effects
				(font
					(size 1.27 1.27)
				)
				(justify left bottom)
				(hide yes)
			)
		)
		(pin "2"
		)
		(pin "1"
		)
		(instances
			(project "com-express-7-baseboard"
				(path ""
					(reference "C7")
					(unit 1)
				)
			)
		)
	)
	(symbol
		(lib_id "antmicroResistors0402:R_10k_0402")
		(at 148.59 78.74 90)
		(unit 1)
		(exclude_from_sim no)
		(in_bom yes)
		(on_board yes)
		(dnp no)
		(property "Reference" "R156"
			(at 149.86 74.93 90)
			(effects
				(font
					(size 1.27 1.27)
					(thickness 0.15)
				)
				(justify right)
			)
		)
		(property "Value" "R_10k_0402"
			(at 161.29 58.42 0)
			(effects
				(font
					(size 1.27 1.27)
					(thickness 0.15)
				)
				(justify left bottom)
				(hide yes)
			)
		)
		(property "Footprint" "antmicro-footprints:R_0402_1005Metric"
			(at 163.83 58.42 0)
			(effects
				(font
					(size 1.27 1.27)
					(thickness 0.15)
				)
				(justify left bottom)
				(hide yes)
			)
		)
		(property "Datasheet" "https://www.bourns.com/docs/product-datasheets/cr.pdf"
			(at 166.37 58.42 0)
			(effects
				(font
					(size 1.27 1.27)
					(thickness 0.15)
				)
				(justify left bottom)
				(hide yes)
			)
		)
		(property "Description" ""
			(at 148.59 78.74 0)
			(effects
				(font
					(size 1.27 1.27)
				)
				(hide yes)
			)
		)
		(property "MPN" "CR0402-FX-1002GLF"
			(at 168.91 58.42 0)
			(effects
				(font
					(size 1.27 1.27)
					(thickness 0.15)
				)
				(justify left bottom)
				(hide yes)
			)
		)
		(property "Manufacturer" "Bourns"
			(at 171.45 58.42 0)
			(effects
				(font
					(size 1.27 1.27)
					(thickness 0.15)
				)
				(justify left bottom)
				(hide yes)
			)
		)
		(property "License" "Apache-2.0"
			(at 173.99 58.42 0)
			(effects
				(font
					(size 1.27 1.27)
					(thickness 0.15)
				)
				(justify left bottom)
				(hide yes)
			)
		)
		(property "Author" "Antmicro"
			(at 176.53 58.42 0)
			(effects
				(font
					(size 1.27 1.27)
					(thickness 0.15)
				)
				(justify left bottom)
				(hide yes)
			)
		)
		(property "Val" "10k"
			(at 149.86 77.47 90)
			(effects
				(font
					(size 1.27 1.27)
					(thickness 0.15)
				)
				(justify right)
			)
		)
		(property "Tolerance" "1%"
			(at 158.75 58.42 0)
			(effects
				(font
					(size 1.27 1.27)
				)
				(justify left bottom)
				(hide yes)
			)
		)
		(property "Public" "False"
			(at 179.07 58.42 0)
			(effects
				(font
					(size 1.27 1.27)
				)
				(justify left bottom)
				(hide yes)
			)
		)
		(pin "1"
		)
		(pin "2"
		)
		(instances
			(project "com-express-7-baseboard"
				(path ""
					(reference "R156")
					(unit 1)
				)
			)
		)
	)
	(symbol
		(lib_id "antmicropower:+1V8")
		(at 60.96 67.31 0)
		(unit 1)
		(exclude_from_sim no)
		(in_bom yes)
		(on_board yes)
		(dnp no)
		(property "Reference" "#PWR0186"
			(at 76.2 69.85 0)
			(effects
				(font
					(size 1.27 1.27)
					(thickness 0.15)
				)
				(justify left bottom)
				(hide yes)
			)
		)
		(property "Value" "+1V8"
			(at 60.96 63.5 0)
			(effects
				(font
					(size 1.27 1.27)
					(thickness 0.15)
				)
			)
		)
		(property "Footprint" ""
			(at 76.2 74.93 0)
			(effects
				(font
					(size 1.27 1.27)
					(thickness 0.15)
				)
				(justify left bottom)
				(hide yes)
			)
		)
		(property "Datasheet" ""
			(at 76.2 77.47 0)
			(effects
				(font
					(size 1.27 1.27)
					(thickness 0.15)
				)
				(justify left bottom)
				(hide yes)
			)
		)
		(property "Description" ""
			(at 60.96 67.31 0)
			(effects
				(font
					(size 1.27 1.27)
				)
				(hide yes)
			)
		)
		(property "Author" "Antmicro"
			(at 76.2 72.39 0)
			(effects
				(font
					(size 1.27 1.27)
					(thickness 0.15)
				)
				(justify left bottom)
				(hide yes)
			)
		)
		(property "License" "Apache-2.0"
			(at 76.2 74.93 0)
			(effects
				(font
					(size 1.27 1.27)
					(thickness 0.15)
				)
				(justify left bottom)
				(hide yes)
			)
		)
		(pin "1"
		)
		(instances
			(project "com-express-7-baseboard"
				(path ""
					(reference "#PWR0186")
					(unit 1)
				)
			)
		)
	)
	(symbol
		(lib_id "antmicropower:GND")
		(at 335.28 214.63 0)
		(unit 1)
		(exclude_from_sim no)
		(in_bom yes)
		(on_board yes)
		(dnp no)
		(property "Reference" "#PWR0219"
			(at 344.17 217.17 0)
			(effects
				(font
					(size 1.27 1.27)
					(thickness 0.15)
				)
				(justify left bottom)
				(hide yes)
			)
		)
		(property "Value" "GND"
			(at 335.28 218.44 0)
			(effects
				(font
					(size 1.27 1.27)
					(thickness 0.15)
				)
			)
		)
		(property "Footprint" ""
			(at 344.17 222.25 0)
			(effects
				(font
					(size 1.27 1.27)
					(thickness 0.15)
				)
				(justify left bottom)
				(hide yes)
			)
		)
		(property "Datasheet" ""
			(at 344.17 227.33 0)
			(effects
				(font
					(size 1.27 1.27)
					(thickness 0.15)
				)
				(justify left bottom)
				(hide yes)
			)
		)
		(property "Description" ""
			(at 335.28 214.63 0)
			(effects
				(font
					(size 1.27 1.27)
				)
				(hide yes)
			)
		)
		(property "Author" "Antmicro"
			(at 344.17 222.25 0)
			(effects
				(font
					(size 1.27 1.27)
					(thickness 0.15)
				)
				(justify left bottom)
				(hide yes)
			)
		)
		(property "License" "Apache-2.0"
			(at 344.17 224.79 0)
			(effects
				(font
					(size 1.27 1.27)
					(thickness 0.15)
				)
				(justify left bottom)
				(hide yes)
			)
		)
		(pin "1"
		)
		(instances
			(project "com-express-7-baseboard"
				(path ""
					(reference "#PWR0219")
					(unit 1)
				)
			)
		)
	)
	(symbol
		(lib_id "antmicroTemperatureSensorsAnalogandDigitalOutput:ADT7476AARQZ")
		(at 96.52 66.04 0)
		(unit 1)
		(exclude_from_sim no)
		(in_bom yes)
		(on_board yes)
		(dnp no)
		(fields_autoplaced yes)
		(property "Reference" "U24"
			(at 113.03 58.42 0)
			(effects
				(font
					(size 1.27 1.27)
				)
			)
		)
		(property "Value" "ADT7476AARQZ"
			(at 96.52 66.04 0)
			(effects
				(font
					(size 1.27 1.27)
				)
				(hide yes)
			)
		)
		(property "Footprint" "antmicro-footprints:QSOP-24_8.65x6mm_P0.635mm"
			(at 96.52 66.04 0)
			(effects
				(font
					(size 1.27 1.27)
				)
				(hide yes)
			)
		)
		(property "Datasheet" "https://www.onsemi.com/pdf/datasheet/adt7476a-d.pdf"
			(at 96.52 66.04 0)
			(effects
				(font
					(size 1.27 1.27)
				)
				(hide yes)
			)
		)
		(property "Description" ""
			(at 96.52 66.04 0)
			(effects
				(font
					(size 1.27 1.27)
				)
				(hide yes)
			)
		)
		(property "MPN" "ADT7476AARQZ"
			(at 113.03 60.96 0)
			(effects
				(font
					(size 1.27 1.27)
				)
			)
		)
		(property "Manufacturer" "Onsemi"
			(at 96.52 66.04 0)
			(effects
				(font
					(size 1.27 1.27)
				)
				(hide yes)
			)
		)
		(property "Author" "Antmicro"
			(at 144.78 83.82 0)
			(effects
				(font
					(size 1.27 1.27)
					(thickness 0.15)
				)
				(justify left bottom)
				(hide yes)
			)
		)
		(property "License" "Apache-2.0"
			(at 144.78 86.36 0)
			(effects
				(font
					(size 1.27 1.27)
					(thickness 0.15)
				)
				(justify left bottom)
				(hide yes)
			)
		)
		(pin "5"
		)
		(pin "6"
		)
		(pin "17"
		)
		(pin "7"
		)
		(pin "1"
		)
		(pin "8"
		)
		(pin "13"
		)
		(pin "10"
		)
		(pin "15"
		)
		(pin "16"
		)
		(pin "12"
		)
		(pin "11"
		)
		(pin "24"
		)
		(pin "22"
		)
		(pin "20"
		)
		(pin "14"
		)
		(pin "21"
		)
		(pin "18"
		)
		(pin "19"
		)
		(pin "2"
		)
		(pin "9"
		)
		(pin "23"
		)
		(pin "4"
		)
		(pin "3"
		)
		(instances
			(project "com-express-7-baseboard"
				(path ""
					(reference "U24")
					(unit 1)
				)
			)
		)
	)
	(symbol
		(lib_id "antmicropower:GND")
		(at 97.79 237.49 0)
		(mirror y)
		(unit 1)
		(exclude_from_sim no)
		(in_bom yes)
		(on_board yes)
		(dnp no)
		(property "Reference" "#PWR0196"
			(at 88.9 240.03 0)
			(effects
				(font
					(size 1.27 1.27)
					(thickness 0.15)
				)
				(justify left bottom)
				(hide yes)
			)
		)
		(property "Value" "GND"
			(at 97.79 241.3 0)
			(effects
				(font
					(size 1.27 1.27)
					(thickness 0.15)
				)
			)
		)
		(property "Footprint" ""
			(at 88.9 245.11 0)
			(effects
				(font
					(size 1.27 1.27)
					(thickness 0.15)
				)
				(justify left bottom)
				(hide yes)
			)
		)
		(property "Datasheet" ""
			(at 88.9 250.19 0)
			(effects
				(font
					(size 1.27 1.27)
					(thickness 0.15)
				)
				(justify left bottom)
				(hide yes)
			)
		)
		(property "Description" ""
			(at 97.79 237.49 0)
			(effects
				(font
					(size 1.27 1.27)
				)
				(hide yes)
			)
		)
		(property "Author" "Antmicro"
			(at 88.9 245.11 0)
			(effects
				(font
					(size 1.27 1.27)
					(thickness 0.15)
				)
				(justify left bottom)
				(hide yes)
			)
		)
		(property "License" "Apache-2.0"
			(at 88.9 247.65 0)
			(effects
				(font
					(size 1.27 1.27)
					(thickness 0.15)
				)
				(justify left bottom)
				(hide yes)
			)
		)
		(pin "1"
		)
		(instances
			(project "com-express-7-baseboard"
				(path ""
					(reference "#PWR0196")
					(unit 1)
				)
			)
		)
	)
	(symbol
		(lib_id "antmicroTransistorsFETsMOSFETsSingle:BSS138-7-F")
		(at 57.15 53.34 0)
		(unit 1)
		(exclude_from_sim no)
		(in_bom yes)
		(on_board yes)
		(dnp no)
		(property "Reference" "Q5"
			(at 67.31 49.53 0)
			(effects
				(font
					(size 1.27 1.27)
					(thickness 0.15)
				)
				(justify left)
			)
		)
		(property "Value" "BSS138-7-F"
			(at 68.58 52.07 0)
			(effects
				(font
					(size 1.27 1.27)
					(thickness 0.15)
				)
				(justify left)
				(hide yes)
			)
		)
		(property "Footprint" "antmicro-footprints:SOT-23-3"
			(at 80.01 60.96 0)
			(effects
				(font
					(size 1.27 1.27)
					(thickness 0.15)
				)
				(justify left bottom)
				(hide yes)
			)
		)
		(property "Datasheet" "https://www.diodes.com/assets/Datasheets/ds30144.pdf"
			(at 80.01 63.5 0)
			(effects
				(font
					(size 1.27 1.27)
					(thickness 0.15)
				)
				(justify left bottom)
				(hide yes)
			)
		)
		(property "Description" ""
			(at 57.15 53.34 0)
			(effects
				(font
					(size 1.27 1.27)
				)
				(hide yes)
			)
		)
		(property "MPN" "BSS138-7-F"
			(at 67.31 53.34 0)
			(effects
				(font
					(size 1.27 1.27)
					(thickness 0.15)
				)
				(justify left bottom)
			)
		)
		(property "Manufacturer" "Diodes Incorporated"
			(at 80.01 68.58 0)
			(effects
				(font
					(size 1.27 1.27)
					(thickness 0.15)
				)
				(justify left bottom)
				(hide yes)
			)
		)
		(property "Author" "Antmicro"
			(at 80.01 71.12 0)
			(effects
				(font
					(size 1.27 1.27)
					(thickness 0.15)
				)
				(justify left bottom)
				(hide yes)
			)
		)
		(property "License" "Apache-2.0"
			(at 80.01 73.66 0)
			(effects
				(font
					(size 1.27 1.27)
					(thickness 0.15)
				)
				(justify left bottom)
				(hide yes)
			)
		)
		(pin "1"
		)
		(pin "2"
		)
		(pin "3"
		)
		(instances
			(project "com-express-7-baseboard"
				(path ""
					(reference "Q5")
					(unit 1)
				)
			)
		)
	)
	(symbol
		(lib_id "antmicropower:+3V3")
		(at 271.78 107.95 0)
		(unit 1)
		(exclude_from_sim no)
		(in_bom yes)
		(on_board yes)
		(dnp no)
		(property "Reference" "#PWR0200"
			(at 287.02 107.95 0)
			(effects
				(font
					(size 1.27 1.27)
					(thickness 0.15)
				)
				(justify left bottom)
				(hide yes)
			)
		)
		(property "Value" "+3V3"
			(at 271.78 104.14 0)
			(effects
				(font
					(size 1.27 1.27)
					(thickness 0.15)
				)
			)
		)
		(property "Footprint" ""
			(at 287.02 115.57 0)
			(effects
				(font
					(size 1.27 1.27)
					(thickness 0.15)
				)
				(justify left bottom)
				(hide yes)
			)
		)
		(property "Datasheet" ""
			(at 287.02 118.11 0)
			(effects
				(font
					(size 1.27 1.27)
					(thickness 0.15)
				)
				(justify left bottom)
				(hide yes)
			)
		)
		(property "Description" ""
			(at 271.78 107.95 0)
			(effects
				(font
					(size 1.27 1.27)
				)
				(hide yes)
			)
		)
		(property "Author" "Antmicro"
			(at 287.02 110.49 0)
			(effects
				(font
					(size 1.27 1.27)
					(thickness 0.15)
				)
				(justify left bottom)
				(hide yes)
			)
		)
		(property "License" "Apache-2.0"
			(at 287.02 113.03 0)
			(effects
				(font
					(size 1.27 1.27)
					(thickness 0.15)
				)
				(justify left bottom)
				(hide yes)
			)
		)
		(pin "1"
		)
		(instances
			(project "com-express-7-baseboard"
				(path ""
					(reference "#PWR0200")
					(unit 1)
				)
			)
		)
	)
	(symbol
		(lib_id "antmicroResistors0402:R_10k_0402")
		(at 69.85 111.76 90)
		(unit 1)
		(exclude_from_sim no)
		(in_bom yes)
		(on_board yes)
		(dnp no)
		(fields_autoplaced yes)
		(property "Reference" "R145"
			(at 72.39 107.95 90)
			(effects
				(font
					(size 1.27 1.27)
					(thickness 0.15)
				)
				(justify right)
			)
		)
		(property "Value" "R_10k_0402"
			(at 82.55 91.44 0)
			(effects
				(font
					(size 1.27 1.27)
					(thickness 0.15)
				)
				(justify left bottom)
				(hide yes)
			)
		)
		(property "Footprint" "antmicro-footprints:R_0402_1005Metric"
			(at 85.09 91.44 0)
			(effects
				(font
					(size 1.27 1.27)
					(thickness 0.15)
				)
				(justify left bottom)
				(hide yes)
			)
		)
		(property "Datasheet" "https://www.bourns.com/docs/product-datasheets/cr.pdf"
			(at 87.63 91.44 0)
			(effects
				(font
					(size 1.27 1.27)
					(thickness 0.15)
				)
				(justify left bottom)
				(hide yes)
			)
		)
		(property "Description" ""
			(at 69.85 111.76 0)
			(effects
				(font
					(size 1.27 1.27)
				)
				(hide yes)
			)
		)
		(property "MPN" "CR0402-FX-1002GLF"
			(at 90.17 91.44 0)
			(effects
				(font
					(size 1.27 1.27)
					(thickness 0.15)
				)
				(justify left bottom)
				(hide yes)
			)
		)
		(property "Manufacturer" "Bourns"
			(at 92.71 91.44 0)
			(effects
				(font
					(size 1.27 1.27)
					(thickness 0.15)
				)
				(justify left bottom)
				(hide yes)
			)
		)
		(property "License" "Apache-2.0"
			(at 95.25 91.44 0)
			(effects
				(font
					(size 1.27 1.27)
					(thickness 0.15)
				)
				(justify left bottom)
				(hide yes)
			)
		)
		(property "Author" "Antmicro"
			(at 97.79 91.44 0)
			(effects
				(font
					(size 1.27 1.27)
					(thickness 0.15)
				)
				(justify left bottom)
				(hide yes)
			)
		)
		(property "Val" "10k"
			(at 72.39 110.49 90)
			(effects
				(font
					(size 1.27 1.27)
					(thickness 0.15)
				)
				(justify right)
			)
		)
		(property "Tolerance" "1%"
			(at 80.01 91.44 0)
			(effects
				(font
					(size 1.27 1.27)
				)
				(justify left bottom)
				(hide yes)
			)
		)
		(property "Public" "False"
			(at 100.33 91.44 0)
			(effects
				(font
					(size 1.27 1.27)
				)
				(justify left bottom)
				(hide yes)
			)
		)
		(pin "1"
		)
		(pin "2"
		)
		(instances
			(project "com-express-7-baseboard"
				(path ""
					(reference "R145")
					(unit 1)
				)
			)
		)
	)
	(symbol
		(lib_id "antmicropower:PWR_FLAG")
		(at 91.44 33.02 0)
		(unit 1)
		(exclude_from_sim no)
		(in_bom yes)
		(on_board yes)
		(dnp no)
		(property "Reference" "#FLG015"
			(at 91.44 31.115 0)
			(effects
				(font
					(size 1.27 1.27)
				)
				(hide yes)
			)
		)
		(property "Value" "PWR_FLAG"
			(at 91.44 29.21 0)
			(effects
				(font
					(size 1.27 1.27)
				)
			)
		)
		(property "Footprint" ""
			(at 91.44 33.02 0)
			(effects
				(font
					(size 1.27 1.27)
				)
				(hide yes)
			)
		)
		(property "Datasheet" ""
			(at 91.44 33.02 0)
			(effects
				(font
					(size 1.27 1.27)
				)
				(hide yes)
			)
		)
		(property "Description" ""
			(at 91.44 33.02 0)
			(effects
				(font
					(size 1.27 1.27)
				)
				(hide yes)
			)
		)
		(pin "1"
		)
		(instances
			(project "com-express-7-baseboard"
				(path ""
					(reference "#FLG015")
					(unit 1)
				)
			)
		)
	)
	(symbol
		(lib_id "antmicroLEDIndicationDiscrete:LED_RGB_PLCC4_ASMB_MTB1_0A3A2")
		(at 59.69 207.01 270)
		(mirror x)
		(unit 1)
		(exclude_from_sim no)
		(in_bom yes)
		(on_board yes)
		(dnp no)
		(fields_autoplaced yes)
		(property "Reference" "D17"
			(at 64.77 196.215 90)
			(effects
				(font
					(size 1.27 1.27)
				)
				(justify left)
			)
		)
		(property "Value" "LED_RGB_PLCC4_ASMB_MTB1_0A3A2"
			(at 49.53 173.99 0)
			(effects
				(font
					(size 1.27 1.27)
				)
				(justify left bottom)
				(hide yes)
			)
		)
		(property "Footprint" "antmicro-footprints:PLCC4_3.2x2.8mm"
			(at 46.99 173.99 0)
			(effects
				(font
					(size 1.27 1.27)
				)
				(justify left bottom)
				(hide yes)
			)
		)
		(property "Datasheet" "https://docs.broadcom.com/doc/AV02-4194EN"
			(at 44.45 173.99 0)
			(effects
				(font
					(size 1.27 1.27)
				)
				(justify left bottom)
				(hide yes)
			)
		)
		(property "Description" ""
			(at 59.69 207.01 0)
			(effects
				(font
					(size 1.27 1.27)
				)
				(hide yes)
			)
		)
		(property "MPN" "ASMB-MTB1-0A3A2"
			(at 52.07 173.99 0)
			(effects
				(font
					(size 1.27 1.27)
				)
				(justify left bottom)
				(hide yes)
			)
		)
		(property "Manufacturer" "Avago Technologies"
			(at 41.91 173.99 0)
			(effects
				(font
					(size 1.27 1.27)
				)
				(justify left bottom)
				(hide yes)
			)
		)
		(property "Color" "R, G, B"
			(at 64.77 198.755 90)
			(effects
				(font
					(size 1.27 1.27)
				)
				(justify left)
			)
		)
		(property "Author" "Antmicro"
			(at 39.37 173.99 0)
			(effects
				(font
					(size 1.27 1.27)
				)
				(justify left bottom)
				(hide yes)
			)
		)
		(property "License" "Apache-2.0"
			(at 36.83 173.99 0)
			(effects
				(font
					(size 1.27 1.27)
				)
				(justify left bottom)
				(hide yes)
			)
		)
		(pin "2"
		)
		(pin "1"
		)
		(pin "3"
		)
		(pin "4"
		)
		(instances
			(project "com-express-7-baseboard"
				(path ""
					(reference "D17")
					(unit 1)
				)
			)
		)
	)
	(symbol
		(lib_id "antmicroTransistorsFETsMOSFETsSingle:BSS138-7-F")
		(at 93.98 247.65 0)
		(unit 1)
		(exclude_from_sim no)
		(in_bom yes)
		(on_board yes)
		(dnp no)
		(property "Reference" "Q8"
			(at 105.41 243.8399 0)
			(effects
				(font
					(size 1.27 1.27)
					(thickness 0.15)
				)
				(justify left)
			)
		)
		(property "Value" "BSS138-7-F"
			(at 105.41 246.3799 0)
			(effects
				(font
					(size 1.27 1.27)
					(thickness 0.15)
				)
				(justify left)
				(hide yes)
			)
		)
		(property "Footprint" "antmicro-footprints:SOT-23-3"
			(at 116.84 255.27 0)
			(effects
				(font
					(size 1.27 1.27)
					(thickness 0.15)
				)
				(justify left bottom)
				(hide yes)
			)
		)
		(property "Datasheet" "https://www.diodes.com/assets/Datasheets/ds30144.pdf"
			(at 116.84 257.81 0)
			(effects
				(font
					(size 1.27 1.27)
					(thickness 0.15)
				)
				(justify left bottom)
				(hide yes)
			)
		)
		(property "Description" ""
			(at 93.98 247.65 0)
			(effects
				(font
					(size 1.27 1.27)
				)
				(hide yes)
			)
		)
		(property "MPN" "BSS138-7-F"
			(at 105.41 247.65 0)
			(effects
				(font
					(size 1.27 1.27)
					(thickness 0.15)
				)
				(justify left bottom)
			)
		)
		(property "Manufacturer" "Diodes Incorporated"
			(at 116.84 262.89 0)
			(effects
				(font
					(size 1.27 1.27)
					(thickness 0.15)
				)
				(justify left bottom)
				(hide yes)
			)
		)
		(property "Author" "Antmicro"
			(at 116.84 265.43 0)
			(effects
				(font
					(size 1.27 1.27)
					(thickness 0.15)
				)
				(justify left bottom)
				(hide yes)
			)
		)
		(property "License" "Apache-2.0"
			(at 116.84 267.97 0)
			(effects
				(font
					(size 1.27 1.27)
					(thickness 0.15)
				)
				(justify left bottom)
				(hide yes)
			)
		)
		(pin "1"
		)
		(pin "3"
		)
		(pin "2"
		)
		(instances
			(project "com-express-7-baseboard"
				(path ""
					(reference "Q8")
					(unit 1)
				)
			)
		)
	)
	(symbol
		(lib_id "antmicroMechanicalParts:Lightpipe_Bivar_SLP3-300-250-F")
		(at 29.21 256.54 0)
		(unit 1)
		(exclude_from_sim no)
		(in_bom yes)
		(on_board yes)
		(dnp no)
		(fields_autoplaced yes)
		(property "Reference" "H4"
			(at 35.56 254.9717 0)
			(effects
				(font
					(size 1.27 1.27)
					(thickness 0.15)
				)
				(justify left)
			)
		)
		(property "Value" "Lightpipe_Bivar_SLP3-300-250-F"
			(at 40.97 263.855 0)
			(effects
				(font
					(size 1.27 1.27)
					(thickness 0.15)
				)
				(justify left bottom)
				(hide yes)
			)
		)
		(property "Footprint" "antmicro-footprints:Mech_Lightpipe_Bivar_SLP3-300-250-F"
			(at 40.97 266.395 0)
			(effects
				(font
					(size 1.27 1.27)
					(thickness 0.15)
				)
				(justify left bottom)
				(hide yes)
			)
		)
		(property "Datasheet" "https://www.bivar.com/parts_content/Datasheets/SLP3-XXX-XXX-X.pdf"
			(at 40.97 268.935 0)
			(effects
				(font
					(size 1.27 1.27)
					(thickness 0.15)
				)
				(justify left bottom)
				(hide yes)
			)
		)
		(property "Description" ""
			(at 29.21 256.54 0)
			(effects
				(font
					(size 1.27 1.27)
				)
				(hide yes)
			)
		)
		(property "Manufacturer" "BIVAR"
			(at 40.97 271.475 0)
			(effects
				(font
					(size 1.27 1.27)
					(thickness 0.15)
				)
				(justify left bottom)
				(hide yes)
			)
		)
		(property "MPN" "SLP3-150-300-F"
			(at 35.56 257.5117 0)
			(effects
				(font
					(size 1.27 1.27)
					(thickness 0.15)
				)
				(justify left)
			)
		)
		(property "Author" "Antmicro"
			(at 40.97 274.015 0)
			(effects
				(font
					(size 1.27 1.27)
					(thickness 0.15)
				)
				(justify left bottom)
				(hide yes)
			)
		)
		(property "License" "Apache-2.0"
			(at 40.97 276.555 0)
			(effects
				(font
					(size 1.27 1.27)
					(thickness 0.15)
				)
				(justify left bottom)
				(hide yes)
			)
		)
		(instances
			(project "com-express-7-baseboard"
				(path ""
					(reference "H4")
					(unit 1)
				)
			)
		)
	)
	(symbol
		(lib_id "antmicropower:GND")
		(at 69.85 123.19 0)
		(unit 1)
		(exclude_from_sim no)
		(in_bom yes)
		(on_board yes)
		(dnp no)
		(property "Reference" "#PWR0190"
			(at 78.74 125.73 0)
			(effects
				(font
					(size 1.27 1.27)
					(thickness 0.15)
				)
				(justify left bottom)
				(hide yes)
			)
		)
		(property "Value" "GND"
			(at 69.85 127 0)
			(effects
				(font
					(size 1.27 1.27)
					(thickness 0.15)
				)
			)
		)
		(property "Footprint" ""
			(at 78.74 130.81 0)
			(effects
				(font
					(size 1.27 1.27)
					(thickness 0.15)
				)
				(justify left bottom)
				(hide yes)
			)
		)
		(property "Datasheet" ""
			(at 78.74 135.89 0)
			(effects
				(font
					(size 1.27 1.27)
					(thickness 0.15)
				)
				(justify left bottom)
				(hide yes)
			)
		)
		(property "Description" ""
			(at 69.85 123.19 0)
			(effects
				(font
					(size 1.27 1.27)
				)
				(hide yes)
			)
		)
		(property "Author" "Antmicro"
			(at 78.74 130.81 0)
			(effects
				(font
					(size 1.27 1.27)
					(thickness 0.15)
				)
				(justify left bottom)
				(hide yes)
			)
		)
		(property "License" "Apache-2.0"
			(at 78.74 133.35 0)
			(effects
				(font
					(size 1.27 1.27)
					(thickness 0.15)
				)
				(justify left bottom)
				(hide yes)
			)
		)
		(pin "1"
		)
		(instances
			(project "com-express-7-baseboard"
				(path ""
					(reference "#PWR0190")
					(unit 1)
				)
			)
		)
	)
	(symbol
		(lib_id "antmicroTransistorsBipolarSingle:MMBT3904LT1G")
		(at 162.56 101.6 0)
		(unit 1)
		(exclude_from_sim no)
		(in_bom yes)
		(on_board yes)
		(dnp no)
		(fields_autoplaced yes)
		(property "Reference" "Q9"
			(at 171.45 100.33 0)
			(effects
				(font
					(size 1.27 1.27)
					(thickness 0.15)
				)
				(justify left)
			)
		)
		(property "Value" "MMBT3904LT1G"
			(at 177.8 111.76 0)
			(effects
				(font
					(size 1.27 1.27)
					(thickness 0.15)
				)
				(justify left bottom)
				(hide yes)
			)
		)
		(property "Footprint" "antmicro-footprints:SOT-23-3"
			(at 177.8 114.3 0)
			(effects
				(font
					(size 1.27 1.27)
					(thickness 0.15)
				)
				(justify left bottom)
				(hide yes)
			)
		)
		(property "Datasheet" "https://eu.mouser.com/datasheet/2/308/1/MMBT3904LT1_D-2316262.pdf"
			(at 177.8 116.84 0)
			(effects
				(font
					(size 1.27 1.27)
					(thickness 0.15)
				)
				(justify left bottom)
				(hide yes)
			)
		)
		(property "Description" ""
			(at 162.56 101.6 0)
			(effects
				(font
					(size 1.27 1.27)
				)
				(hide yes)
			)
		)
		(property "MPN" "MMBT3904LT1G"
			(at 171.45 102.87 0)
			(effects
				(font
					(size 1.27 1.27)
					(thickness 0.15)
				)
				(justify left)
			)
		)
		(property "Manufacturer" "Onsemi"
			(at 177.8 119.38 0)
			(effects
				(font
					(size 1.27 1.27)
					(thickness 0.15)
				)
				(justify left bottom)
				(hide yes)
			)
		)
		(property "Author" "Antmicro"
			(at 177.8 121.92 0)
			(effects
				(font
					(size 1.27 1.27)
					(thickness 0.15)
				)
				(justify left bottom)
				(hide yes)
			)
		)
		(property "License" "Apache-2.0"
			(at 177.8 124.46 0)
			(effects
				(font
					(size 1.27 1.27)
					(thickness 0.15)
				)
				(justify left bottom)
				(hide yes)
			)
		)
		(property "Public" "False"
			(at 185.42 121.92 0)
			(effects
				(font
					(size 1.27 1.27)
				)
				(justify left bottom)
				(hide yes)
			)
		)
		(pin "2"
		)
		(pin "1"
		)
		(pin "3"
		)
		(instances
			(project "com-express-7-baseboard"
				(path ""
					(reference "Q9")
					(unit 1)
				)
			)
		)
	)
	(symbol
		(lib_id "antmicroTestPoints:TP_0.75mm_SMD")
		(at 139.7 68.58 0)
		(unit 1)
		(exclude_from_sim no)
		(in_bom no)
		(on_board yes)
		(dnp no)
		(property "Reference" "TP15"
			(at 142.24 66.04 0)
			(effects
				(font
					(size 1.27 1.27)
					(thickness 0.15)
				)
				(justify left)
			)
		)
		(property "Value" "TP_0.75mm_SMD"
			(at 150.495 72.39 0)
			(effects
				(font
					(size 1.27 1.27)
					(thickness 0.15)
				)
				(justify left bottom)
				(hide yes)
			)
		)
		(property "Footprint" "antmicro-footprints:TP_SMD_0.75mm"
			(at 150.495 74.93 0)
			(effects
				(font
					(size 1.27 1.27)
					(thickness 0.15)
				)
				(justify left bottom)
				(hide yes)
			)
		)
		(property "Datasheet" ""
			(at 157.48 81.28 0)
			(effects
				(font
					(size 1.27 1.27)
					(thickness 0.15)
				)
				(justify left bottom)
				(hide yes)
			)
		)
		(property "Description" ""
			(at 139.7 68.58 0)
			(effects
				(font
					(size 1.27 1.27)
				)
				(hide yes)
			)
		)
		(property "MPN" ""
			(at 150.495 80.01 0)
			(effects
				(font
					(size 1.27 1.27)
					(thickness 0.15)
				)
				(justify left bottom)
				(hide yes)
			)
		)
		(property "Manufacturer" ""
			(at 150.495 74.93 0)
			(effects
				(font
					(size 1.27 1.27)
					(thickness 0.15)
				)
				(justify left bottom)
				(hide yes)
			)
		)
		(property "Author" "Antmicro"
			(at 150.495 77.47 0)
			(effects
				(font
					(size 1.27 1.27)
					(thickness 0.15)
				)
				(justify left bottom)
				(hide yes)
			)
		)
		(property "License" "Apache-2.0"
			(at 150.495 80.01 0)
			(effects
				(font
					(size 1.27 1.27)
					(thickness 0.15)
				)
				(justify left bottom)
				(hide yes)
			)
		)
		(property "Public" "False"
			(at 149.86 82.55 0)
			(effects
				(font
					(size 1.27 1.27)
				)
				(justify left bottom)
				(hide yes)
			)
		)
		(pin "1"
		)
		(instances
			(project "com-express-7-baseboard"
				(path ""
					(reference "TP15")
					(unit 1)
				)
			)
		)
	)
	(symbol
		(lib_name "R_10k_0402_1")
		(lib_id "antmicroResistors0402:R_10k_0402")
		(at 55.88 217.17 90)
		(unit 1)
		(exclude_from_sim no)
		(in_bom yes)
		(on_board yes)
		(dnp no)
		(property "Reference" "R141"
			(at 54.61 222.25 0)
			(effects
				(font
					(size 1.27 1.27)
					(thickness 0.15)
				)
				(justify left)
			)
		)
		(property "Value" "R_10k_0402"
			(at 68.58 196.85 0)
			(effects
				(font
					(size 1.27 1.27)
					(thickness 0.15)
				)
				(justify left bottom)
				(hide yes)
			)
		)
		(property "Footprint" "antmicro-footprints:R_0402_1005Metric"
			(at 71.12 196.85 0)
			(effects
				(font
					(size 1.27 1.27)
					(thickness 0.15)
				)
				(justify left bottom)
				(hide yes)
			)
		)
		(property "Datasheet" "https://www.bourns.com/docs/product-datasheets/cr.pdf"
			(at 73.66 196.85 0)
			(effects
				(font
					(size 1.27 1.27)
					(thickness 0.15)
				)
				(justify left bottom)
				(hide yes)
			)
		)
		(property "Description" "SMD Chip Resistor, 10 kohm, ± 1%, 62.5 mW, 0402 [1005 Metric], Thick Film, General Purpose"
			(at 55.88 217.17 0)
			(effects
				(font
					(size 1.27 1.27)
				)
				(hide yes)
			)
		)
		(property "MPN" "CR0402-FX-1002GLF"
			(at 76.2 196.85 0)
			(effects
				(font
					(size 1.27 1.27)
					(thickness 0.15)
				)
				(justify left bottom)
				(hide yes)
			)
		)
		(property "Manufacturer" "Bourns"
			(at 78.74 196.85 0)
			(effects
				(font
					(size 1.27 1.27)
					(thickness 0.15)
				)
				(justify left bottom)
				(hide yes)
			)
		)
		(property "License" "Apache-2.0"
			(at 81.28 196.85 0)
			(effects
				(font
					(size 1.27 1.27)
					(thickness 0.15)
				)
				(justify left bottom)
				(hide yes)
			)
		)
		(property "Author" "Antmicro"
			(at 83.82 196.85 0)
			(effects
				(font
					(size 1.27 1.27)
					(thickness 0.15)
				)
				(justify left bottom)
				(hide yes)
			)
		)
		(property "Val" "10k"
			(at 54.61 212.09 0)
			(effects
				(font
					(size 1.27 1.27)
					(thickness 0.15)
				)
				(justify left)
			)
		)
		(property "Tolerance" "1%"
			(at 66.04 196.85 0)
			(effects
				(font
					(size 1.27 1.27)
				)
				(justify left bottom)
				(hide yes)
			)
		)
		(pin "2"
		)
		(pin "1"
		)
		(instances
			(project "com-express-7-baseboard"
				(path ""
					(reference "R141")
					(unit 1)
				)
			)
		)
	)
	(symbol
		(lib_id "antmicropower:+5V_AON")
		(at 97.79 187.96 0)
		(unit 1)
		(exclude_from_sim no)
		(in_bom yes)
		(on_board yes)
		(dnp no)
		(property "Reference" "#PWR0195"
			(at 97.79 191.77 0)
			(effects
				(font
					(size 1.27 1.27)
				)
				(hide yes)
			)
		)
		(property "Value" "+5V_AON"
			(at 97.79 184.15 0)
			(effects
				(font
					(size 1.27 1.27)
				)
			)
		)
		(property "Footprint" ""
			(at 97.79 187.96 0)
			(effects
				(font
					(size 1.27 1.27)
				)
				(hide yes)
			)
		)
		(property "Datasheet" ""
			(at 97.79 187.96 0)
			(effects
				(font
					(size 1.27 1.27)
				)
				(hide yes)
			)
		)
		(property "Description" ""
			(at 97.79 187.96 0)
			(effects
				(font
					(size 1.27 1.27)
				)
				(hide yes)
			)
		)
		(pin "1"
		)
		(instances
			(project "com-express-7-baseboard"
				(path ""
					(reference "#PWR0195")
					(unit 1)
				)
			)
		)
	)
	(symbol
		(lib_id "antmicropower:GND")
		(at 64.77 57.15 0)
		(unit 1)
		(exclude_from_sim no)
		(in_bom yes)
		(on_board yes)
		(dnp no)
		(property "Reference" "#PWR0188"
			(at 73.66 59.69 0)
			(effects
				(font
					(size 1.27 1.27)
					(thickness 0.15)
				)
				(justify left bottom)
				(hide yes)
			)
		)
		(property "Value" "GND"
			(at 64.77 60.96 0)
			(effects
				(font
					(size 1.27 1.27)
					(thickness 0.15)
				)
			)
		)
		(property "Footprint" ""
			(at 73.66 64.77 0)
			(effects
				(font
					(size 1.27 1.27)
					(thickness 0.15)
				)
				(justify left bottom)
				(hide yes)
			)
		)
		(property "Datasheet" ""
			(at 73.66 69.85 0)
			(effects
				(font
					(size 1.27 1.27)
					(thickness 0.15)
				)
				(justify left bottom)
				(hide yes)
			)
		)
		(property "Description" ""
			(at 64.77 57.15 0)
			(effects
				(font
					(size 1.27 1.27)
				)
				(hide yes)
			)
		)
		(property "Author" "Antmicro"
			(at 73.66 64.77 0)
			(effects
				(font
					(size 1.27 1.27)
					(thickness 0.15)
				)
				(justify left bottom)
				(hide yes)
			)
		)
		(property "License" "Apache-2.0"
			(at 73.66 67.31 0)
			(effects
				(font
					(size 1.27 1.27)
					(thickness 0.15)
				)
				(justify left bottom)
				(hide yes)
			)
		)
		(pin "1"
		)
		(instances
			(project "com-express-7-baseboard"
				(path ""
					(reference "#PWR0188")
					(unit 1)
				)
			)
		)
	)
	(symbol
		(lib_id "antmicropower:GND")
		(at 335.28 163.83 0)
		(unit 1)
		(exclude_from_sim no)
		(in_bom yes)
		(on_board yes)
		(dnp no)
		(property "Reference" "#PWR0217"
			(at 344.17 166.37 0)
			(effects
				(font
					(size 1.27 1.27)
					(thickness 0.15)
				)
				(justify left bottom)
				(hide yes)
			)
		)
		(property "Value" "GND"
			(at 335.28 167.64 0)
			(effects
				(font
					(size 1.27 1.27)
					(thickness 0.15)
				)
			)
		)
		(property "Footprint" ""
			(at 344.17 171.45 0)
			(effects
				(font
					(size 1.27 1.27)
					(thickness 0.15)
				)
				(justify left bottom)
				(hide yes)
			)
		)
		(property "Datasheet" ""
			(at 344.17 176.53 0)
			(effects
				(font
					(size 1.27 1.27)
					(thickness 0.15)
				)
				(justify left bottom)
				(hide yes)
			)
		)
		(property "Description" ""
			(at 335.28 163.83 0)
			(effects
				(font
					(size 1.27 1.27)
				)
				(hide yes)
			)
		)
		(property "Author" "Antmicro"
			(at 344.17 171.45 0)
			(effects
				(font
					(size 1.27 1.27)
					(thickness 0.15)
				)
				(justify left bottom)
				(hide yes)
			)
		)
		(property "License" "Apache-2.0"
			(at 344.17 173.99 0)
			(effects
				(font
					(size 1.27 1.27)
					(thickness 0.15)
				)
				(justify left bottom)
				(hide yes)
			)
		)
		(pin "1"
		)
		(instances
			(project "com-express-7-baseboard"
				(path ""
					(reference "#PWR0217")
					(unit 1)
				)
			)
		)
	)
	(symbol
		(lib_id "antmicroTestPoints:TP_0.75mm_SMD")
		(at 129.54 93.98 0)
		(unit 1)
		(exclude_from_sim no)
		(in_bom no)
		(on_board yes)
		(dnp no)
		(fields_autoplaced yes)
		(property "Reference" "TP12"
			(at 134.62 93.98 0)
			(effects
				(font
					(size 1.27 1.27)
					(thickness 0.15)
				)
				(justify left)
			)
		)
		(property "Value" "TP_0.75mm_SMD"
			(at 140.335 97.79 0)
			(effects
				(font
					(size 1.27 1.27)
					(thickness 0.15)
				)
				(justify left bottom)
				(hide yes)
			)
		)
		(property "Footprint" "antmicro-footprints:TP_SMD_0.75mm"
			(at 140.335 100.33 0)
			(effects
				(font
					(size 1.27 1.27)
					(thickness 0.15)
				)
				(justify left bottom)
				(hide yes)
			)
		)
		(property "Datasheet" ""
			(at 147.32 106.68 0)
			(effects
				(font
					(size 1.27 1.27)
					(thickness 0.15)
				)
				(justify left bottom)
				(hide yes)
			)
		)
		(property "Description" ""
			(at 129.54 93.98 0)
			(effects
				(font
					(size 1.27 1.27)
				)
				(hide yes)
			)
		)
		(property "MPN" ""
			(at 140.335 105.41 0)
			(effects
				(font
					(size 1.27 1.27)
					(thickness 0.15)
				)
				(justify left bottom)
				(hide yes)
			)
		)
		(property "Manufacturer" ""
			(at 140.335 100.33 0)
			(effects
				(font
					(size 1.27 1.27)
					(thickness 0.15)
				)
				(justify left bottom)
				(hide yes)
			)
		)
		(property "Author" "Antmicro"
			(at 140.335 102.87 0)
			(effects
				(font
					(size 1.27 1.27)
					(thickness 0.15)
				)
				(justify left bottom)
				(hide yes)
			)
		)
		(property "License" "Apache-2.0"
			(at 140.335 105.41 0)
			(effects
				(font
					(size 1.27 1.27)
					(thickness 0.15)
				)
				(justify left bottom)
				(hide yes)
			)
		)
		(property "Public" "False"
			(at 139.7 107.95 0)
			(effects
				(font
					(size 1.27 1.27)
				)
				(justify left bottom)
				(hide yes)
			)
		)
		(pin "1"
		)
		(instances
			(project "com-express-7-baseboard"
				(path ""
					(reference "TP12")
					(unit 1)
				)
			)
		)
	)
	(symbol
		(lib_id "antmicropower:GND")
		(at 335.28 107.95 0)
		(unit 1)
		(exclude_from_sim no)
		(in_bom yes)
		(on_board yes)
		(dnp no)
		(property "Reference" "#PWR0215"
			(at 344.17 110.49 0)
			(effects
				(font
					(size 1.27 1.27)
					(thickness 0.15)
				)
				(justify left bottom)
				(hide yes)
			)
		)
		(property "Value" "GND"
			(at 335.28 111.76 0)
			(effects
				(font
					(size 1.27 1.27)
					(thickness 0.15)
				)
			)
		)
		(property "Footprint" ""
			(at 344.17 115.57 0)
			(effects
				(font
					(size 1.27 1.27)
					(thickness 0.15)
				)
				(justify left bottom)
				(hide yes)
			)
		)
		(property "Datasheet" ""
			(at 344.17 120.65 0)
			(effects
				(font
					(size 1.27 1.27)
					(thickness 0.15)
				)
				(justify left bottom)
				(hide yes)
			)
		)
		(property "Description" ""
			(at 335.28 107.95 0)
			(effects
				(font
					(size 1.27 1.27)
				)
				(hide yes)
			)
		)
		(property "Author" "Antmicro"
			(at 344.17 115.57 0)
			(effects
				(font
					(size 1.27 1.27)
					(thickness 0.15)
				)
				(justify left bottom)
				(hide yes)
			)
		)
		(property "License" "Apache-2.0"
			(at 344.17 118.11 0)
			(effects
				(font
					(size 1.27 1.27)
					(thickness 0.15)
				)
				(justify left bottom)
				(hide yes)
			)
		)
		(pin "1"
		)
		(instances
			(project "com-express-7-baseboard"
				(path ""
					(reference "#PWR0215")
					(unit 1)
				)
			)
		)
	)
	(symbol
		(lib_id "antmicroCapacitors0402:C_100n_0402")
		(at 307.34 205.74 270)
		(mirror x)
		(unit 1)
		(exclude_from_sim no)
		(in_bom yes)
		(on_board yes)
		(dnp no)
		(fields_autoplaced yes)
		(property "Reference" "C88"
			(at 304.8 201.9236 90)
			(effects
				(font
					(size 1.27 1.27)
					(thickness 0.15)
				)
				(justify right)
			)
		)
		(property "Value" "C_100n_0402"
			(at 297.18 185.42 0)
			(effects
				(font
					(size 1.27 1.27)
					(thickness 0.15)
				)
				(justify left bottom)
				(hide yes)
			)
		)
		(property "Footprint" "antmicro-footprints:C_0402_1005Metric"
			(at 294.64 185.42 0)
			(effects
				(font
					(size 1.27 1.27)
					(thickness 0.15)
				)
				(justify left bottom)
				(hide yes)
			)
		)
		(property "Datasheet" "https://www.murata.com/products/productdetail?partno=GRM155R61H104KE14%23"
			(at 292.1 185.42 0)
			(effects
				(font
					(size 1.27 1.27)
					(thickness 0.15)
				)
				(justify left bottom)
				(hide yes)
			)
		)
		(property "Description" ""
			(at 307.34 205.74 0)
			(effects
				(font
					(size 1.27 1.27)
				)
				(hide yes)
			)
		)
		(property "MPN" "GRM155R61H104KE14D"
			(at 289.56 185.42 0)
			(effects
				(font
					(size 1.27 1.27)
					(thickness 0.15)
				)
				(justify left bottom)
				(hide yes)
			)
		)
		(property "Manufacturer" "Murata"
			(at 287.02 185.42 0)
			(effects
				(font
					(size 1.27 1.27)
					(thickness 0.15)
				)
				(justify left bottom)
				(hide yes)
			)
		)
		(property "License" "Apache-2.0"
			(at 284.48 185.42 0)
			(effects
				(font
					(size 1.27 1.27)
					(thickness 0.15)
				)
				(justify left bottom)
				(hide yes)
			)
		)
		(property "Author" "Antmicro"
			(at 281.94 185.42 0)
			(effects
				(font
					(size 1.27 1.27)
					(thickness 0.15)
				)
				(justify left bottom)
				(hide yes)
			)
		)
		(property "Val" "100n"
			(at 304.8 204.4636 90)
			(effects
				(font
					(size 1.27 1.27)
					(thickness 0.15)
				)
				(justify right)
			)
		)
		(property "Voltage" "50V"
			(at 279.4 185.42 0)
			(effects
				(font
					(size 1.27 1.27)
				)
				(justify left bottom)
				(hide yes)
			)
		)
		(property "Dielectric" "X5R"
			(at 276.86 185.42 0)
			(effects
				(font
					(size 1.27 1.27)
				)
				(justify left bottom)
				(hide yes)
			)
		)
		(property "Public" "False"
			(at 274.32 185.42 0)
			(effects
				(font
					(size 1.27 1.27)
				)
				(justify left bottom)
				(hide yes)
			)
		)
		(pin "2"
		)
		(pin "1"
		)
		(instances
			(project "com-express-7-baseboard"
				(path ""
					(reference "C88")
					(unit 1)
				)
			)
		)
	)
	(symbol
		(lib_id "antmicropower:+3V3")
		(at 60.96 101.6 0)
		(unit 1)
		(exclude_from_sim no)
		(in_bom yes)
		(on_board yes)
		(dnp no)
		(property "Reference" "#PWR0187"
			(at 76.2 101.6 0)
			(effects
				(font
					(size 1.27 1.27)
					(thickness 0.15)
				)
				(justify left bottom)
				(hide yes)
			)
		)
		(property "Value" "+3V3"
			(at 60.96 97.79 0)
			(effects
				(font
					(size 1.27 1.27)
					(thickness 0.15)
				)
			)
		)
		(property "Footprint" ""
			(at 76.2 109.22 0)
			(effects
				(font
					(size 1.27 1.27)
					(thickness 0.15)
				)
				(justify left bottom)
				(hide yes)
			)
		)
		(property "Datasheet" ""
			(at 76.2 111.76 0)
			(effects
				(font
					(size 1.27 1.27)
					(thickness 0.15)
				)
				(justify left bottom)
				(hide yes)
			)
		)
		(property "Description" ""
			(at 60.96 101.6 0)
			(effects
				(font
					(size 1.27 1.27)
				)
				(hide yes)
			)
		)
		(property "Author" "Antmicro"
			(at 76.2 104.14 0)
			(effects
				(font
					(size 1.27 1.27)
					(thickness 0.15)
				)
				(justify left bottom)
				(hide yes)
			)
		)
		(property "License" "Apache-2.0"
			(at 76.2 106.68 0)
			(effects
				(font
					(size 1.27 1.27)
					(thickness 0.15)
				)
				(justify left bottom)
				(hide yes)
			)
		)
		(pin "1"
		)
		(instances
			(project "com-express-7-baseboard"
				(path ""
					(reference "#PWR0187")
					(unit 1)
				)
			)
		)
	)
	(symbol
		(lib_id "antmicroCapacitors0402:C_100n_0402")
		(at 271.78 115.57 270)
		(mirror x)
		(unit 1)
		(exclude_from_sim no)
		(in_bom yes)
		(on_board yes)
		(dnp no)
		(property "Reference" "C84"
			(at 271.145 111.125 90)
			(effects
				(font
					(size 1.27 1.27)
					(thickness 0.15)
				)
				(justify right)
			)
		)
		(property "Value" "C_100n_0402"
			(at 261.62 95.25 0)
			(effects
				(font
					(size 1.27 1.27)
					(thickness 0.15)
				)
				(justify left bottom)
				(hide yes)
			)
		)
		(property "Footprint" "antmicro-footprints:C_0402_1005Metric"
			(at 259.08 95.25 0)
			(effects
				(font
					(size 1.27 1.27)
					(thickness 0.15)
				)
				(justify left bottom)
				(hide yes)
			)
		)
		(property "Datasheet" "https://www.murata.com/products/productdetail?partno=GRM155R61H104KE14%23"
			(at 256.54 95.25 0)
			(effects
				(font
					(size 1.27 1.27)
					(thickness 0.15)
				)
				(justify left bottom)
				(hide yes)
			)
		)
		(property "Description" ""
			(at 271.78 115.57 0)
			(effects
				(font
					(size 1.27 1.27)
				)
				(hide yes)
			)
		)
		(property "MPN" "GRM155R61H104KE14D"
			(at 254 95.25 0)
			(effects
				(font
					(size 1.27 1.27)
					(thickness 0.15)
				)
				(justify left bottom)
				(hide yes)
			)
		)
		(property "Manufacturer" "Murata"
			(at 251.46 95.25 0)
			(effects
				(font
					(size 1.27 1.27)
					(thickness 0.15)
				)
				(justify left bottom)
				(hide yes)
			)
		)
		(property "License" "Apache-2.0"
			(at 248.92 95.25 0)
			(effects
				(font
					(size 1.27 1.27)
					(thickness 0.15)
				)
				(justify left bottom)
				(hide yes)
			)
		)
		(property "Author" "Antmicro"
			(at 246.38 95.25 0)
			(effects
				(font
					(size 1.27 1.27)
					(thickness 0.15)
				)
				(justify left bottom)
				(hide yes)
			)
		)
		(property "Val" "100n"
			(at 271.145 114.935 90)
			(effects
				(font
					(size 1.27 1.27)
					(thickness 0.15)
				)
				(justify right)
			)
		)
		(property "Voltage" "50V"
			(at 243.84 95.25 0)
			(effects
				(font
					(size 1.27 1.27)
				)
				(justify left bottom)
				(hide yes)
			)
		)
		(property "Dielectric" "X5R"
			(at 241.3 95.25 0)
			(effects
				(font
					(size 1.27 1.27)
				)
				(justify left bottom)
				(hide yes)
			)
		)
		(property "Public" "False"
			(at 238.76 95.25 0)
			(effects
				(font
					(size 1.27 1.27)
				)
				(justify left bottom)
				(hide yes)
			)
		)
		(pin "2"
		)
		(pin "1"
		)
		(instances
			(project "com-express-7-baseboard"
				(path ""
					(reference "C84")
					(unit 1)
				)
			)
		)
	)
	(symbol
		(lib_id "antmicropower:+12V")
		(at 71.12 67.31 0)
		(unit 1)
		(exclude_from_sim no)
		(in_bom yes)
		(on_board yes)
		(dnp no)
		(property "Reference" "#PWR0191"
			(at 71.12 71.12 0)
			(effects
				(font
					(size 1.27 1.27)
				)
				(hide yes)
			)
		)
		(property "Value" "+12V"
			(at 71.12 63.5 0)
			(effects
				(font
					(size 1.27 1.27)
				)
			)
		)
		(property "Footprint" ""
			(at 71.12 67.31 0)
			(effects
				(font
					(size 1.27 1.27)
				)
				(hide yes)
			)
		)
		(property "Datasheet" ""
			(at 71.12 67.31 0)
			(effects
				(font
					(size 1.27 1.27)
				)
				(hide yes)
			)
		)
		(property "Description" ""
			(at 71.12 67.31 0)
			(effects
				(font
					(size 1.27 1.27)
				)
				(hide yes)
			)
		)
		(pin "1"
		)
		(instances
			(project "com-express-7-baseboard"
				(path ""
					(reference "#PWR0191")
					(unit 1)
				)
			)
		)
	)
	(symbol
		(lib_id "antmicroResistors0402:R_0R_0402")
		(at 139.7 88.9 0)
		(unit 1)
		(exclude_from_sim no)
		(in_bom yes)
		(on_board yes)
		(dnp no)
		(property "Reference" "R154"
			(at 137.16 87.63 0)
			(effects
				(font
					(size 1.27 1.27)
					(thickness 0.15)
				)
			)
		)
		(property "Value" "R_0R_0402"
			(at 160.02 101.6 0)
			(effects
				(font
					(size 1.27 1.27)
					(thickness 0.15)
				)
				(justify left bottom)
				(hide yes)
			)
		)
		(property "Footprint" "antmicro-footprints:R_0402_1005Metric"
			(at 160.02 104.14 0)
			(effects
				(font
					(size 1.27 1.27)
					(thickness 0.15)
				)
				(justify left bottom)
				(hide yes)
			)
		)
		(property "Datasheet" "https://industrial.panasonic.com/cdbs/www-data/pdf/RDA0000/AOA0000C301.pdf"
			(at 160.02 106.68 0)
			(effects
				(font
					(size 1.27 1.27)
					(thickness 0.15)
				)
				(justify left bottom)
				(hide yes)
			)
		)
		(property "Description" ""
			(at 139.7 88.9 0)
			(effects
				(font
					(size 1.27 1.27)
				)
				(hide yes)
			)
		)
		(property "MPN" "ERJ2GE0R00X"
			(at 160.02 109.22 0)
			(effects
				(font
					(size 1.27 1.27)
					(thickness 0.15)
				)
				(justify left bottom)
				(hide yes)
			)
		)
		(property "Manufacturer" "Panasonic"
			(at 160.02 111.76 0)
			(effects
				(font
					(size 1.27 1.27)
					(thickness 0.15)
				)
				(justify left bottom)
				(hide yes)
			)
		)
		(property "License" "Apache-2.0"
			(at 160.02 114.3 0)
			(effects
				(font
					(size 1.27 1.27)
					(thickness 0.15)
				)
				(justify left bottom)
				(hide yes)
			)
		)
		(property "Author" "Antmicro"
			(at 160.02 116.84 0)
			(effects
				(font
					(size 1.27 1.27)
					(thickness 0.15)
				)
				(justify left bottom)
				(hide yes)
			)
		)
		(property "Val" "0R"
			(at 146.05 87.63 0)
			(effects
				(font
					(size 1.27 1.27)
					(thickness 0.15)
				)
			)
		)
		(property "Tolerance" "~"
			(at 160.02 99.06 0)
			(effects
				(font
					(size 1.27 1.27)
				)
				(justify left bottom)
				(hide yes)
			)
		)
		(property "Current" "1A"
			(at 160.02 119.38 0)
			(effects
				(font
					(size 1.27 1.27)
					(thickness 0.15)
				)
				(justify left bottom)
				(hide yes)
			)
		)
		(property "Public" "False"
			(at 160.02 119.38 0)
			(effects
				(font
					(size 1.27 1.27)
				)
				(justify left bottom)
				(hide yes)
			)
		)
		(pin "2"
		)
		(pin "1"
		)
		(instances
			(project "com-express-7-baseboard"
				(path ""
					(reference "R154")
					(unit 1)
				)
			)
		)
	)
	(symbol
		(lib_id "antmicropower:GND")
		(at 307.34 163.83 0)
		(mirror y)
		(unit 1)
		(exclude_from_sim no)
		(in_bom yes)
		(on_board yes)
		(dnp no)
		(property "Reference" "#PWR0210"
			(at 298.45 166.37 0)
			(effects
				(font
					(size 1.27 1.27)
					(thickness 0.15)
				)
				(justify left bottom)
				(hide yes)
			)
		)
		(property "Value" "GND"
			(at 307.34 167.64 0)
			(effects
				(font
					(size 1.27 1.27)
					(thickness 0.15)
				)
			)
		)
		(property "Footprint" ""
			(at 298.45 171.45 0)
			(effects
				(font
					(size 1.27 1.27)
					(thickness 0.15)
				)
				(justify left bottom)
				(hide yes)
			)
		)
		(property "Datasheet" ""
			(at 298.45 176.53 0)
			(effects
				(font
					(size 1.27 1.27)
					(thickness 0.15)
				)
				(justify left bottom)
				(hide yes)
			)
		)
		(property "Description" ""
			(at 307.34 163.83 0)
			(effects
				(font
					(size 1.27 1.27)
				)
				(hide yes)
			)
		)
		(property "Author" "Antmicro"
			(at 298.45 171.45 0)
			(effects
				(font
					(size 1.27 1.27)
					(thickness 0.15)
				)
				(justify left bottom)
				(hide yes)
			)
		)
		(property "License" "Apache-2.0"
			(at 298.45 173.99 0)
			(effects
				(font
					(size 1.27 1.27)
					(thickness 0.15)
				)
				(justify left bottom)
				(hide yes)
			)
		)
		(pin "1"
		)
		(instances
			(project "com-express-7-baseboard"
				(path ""
					(reference "#PWR0210")
					(unit 1)
				)
			)
		)
	)
	(symbol
		(lib_id "antmicropower:+5V")
		(at 335.28 195.58 0)
		(unit 1)
		(exclude_from_sim no)
		(in_bom yes)
		(on_board yes)
		(dnp no)
		(property "Reference" "#PWR0218"
			(at 350.52 198.12 0)
			(effects
				(font
					(size 1.27 1.27)
					(thickness 0.15)
				)
				(justify left bottom)
				(hide yes)
			)
		)
		(property "Value" "+5V"
			(at 335.28 191.77 0)
			(effects
				(font
					(size 1.27 1.27)
					(thickness 0.15)
				)
			)
		)
		(property "Footprint" ""
			(at 350.52 203.2 0)
			(effects
				(font
					(size 1.27 1.27)
					(thickness 0.15)
				)
				(justify left bottom)
				(hide yes)
			)
		)
		(property "Datasheet" ""
			(at 350.52 205.74 0)
			(effects
				(font
					(size 1.27 1.27)
					(thickness 0.15)
				)
				(justify left bottom)
				(hide yes)
			)
		)
		(property "Description" ""
			(at 335.28 195.58 0)
			(effects
				(font
					(size 1.27 1.27)
				)
				(hide yes)
			)
		)
		(property "Author" "Antmicro"
			(at 350.52 203.2 0)
			(effects
				(font
					(size 1.27 1.27)
					(thickness 0.15)
				)
				(justify left bottom)
				(hide yes)
			)
		)
		(property "License" "Apache-2.0"
			(at 350.52 205.74 0)
			(effects
				(font
					(size 1.27 1.27)
					(thickness 0.15)
				)
				(justify left bottom)
				(hide yes)
			)
		)
		(pin "1"
		)
		(instances
			(project "com-express-7-baseboard"
				(path ""
					(reference "#PWR0218")
					(unit 1)
				)
			)
		)
	)
	(symbol
		(lib_id "antmicroLogicTranslatorsLevelShifters:NTS0102_TSSOP")
		(at 311.15 205.74 0)
		(unit 1)
		(exclude_from_sim no)
		(in_bom yes)
		(on_board yes)
		(dnp no)
		(property "Reference" "U29"
			(at 321.31 199.39 0)
			(effects
				(font
					(size 1.27 1.27)
					(thickness 0.15)
				)
			)
		)
		(property "Value" "NTS0102_TSSOP"
			(at 321.31 200.66 0)
			(effects
				(font
					(size 1.27 1.27)
					(thickness 0.15)
				)
				(hide yes)
			)
		)
		(property "Footprint" "antmicro-footprints:TSSOP-8_3x3mm_P0.65mm"
			(at 346.71 214.63 0)
			(effects
				(font
					(size 1.27 1.27)
					(thickness 0.15)
				)
				(justify left bottom)
				(hide yes)
			)
		)
		(property "Datasheet" "https://www.mouser.com/datasheet/2/302/NTS0102-1127324.pdf"
			(at 346.71 217.17 0)
			(effects
				(font
					(size 1.27 1.27)
					(thickness 0.15)
				)
				(justify left bottom)
				(hide yes)
			)
		)
		(property "Description" ""
			(at 311.15 205.74 0)
			(effects
				(font
					(size 1.27 1.27)
				)
				(hide yes)
			)
		)
		(property "MPN" "NTS0102DP"
			(at 316.23 201.93 0)
			(effects
				(font
					(size 1.27 1.27)
					(thickness 0.15)
				)
				(justify left bottom)
			)
		)
		(property "Manufacturer" "NXP"
			(at 346.71 222.25 0)
			(effects
				(font
					(size 1.27 1.27)
					(thickness 0.15)
				)
				(justify left bottom)
				(hide yes)
			)
		)
		(property "Author" "Antmicro"
			(at 346.71 224.79 0)
			(effects
				(font
					(size 1.27 1.27)
					(thickness 0.15)
				)
				(justify left bottom)
				(hide yes)
			)
		)
		(property "License" "Apache-2.0"
			(at 346.71 227.33 0)
			(effects
				(font
					(size 1.27 1.27)
					(thickness 0.15)
				)
				(justify left bottom)
				(hide yes)
			)
		)
		(pin "3"
		)
		(pin "6"
		)
		(pin "7"
		)
		(pin "4"
		)
		(pin "5"
		)
		(pin "2"
		)
		(pin "1"
		)
		(pin "8"
		)
		(instances
			(project "com-express-7-baseboard"
				(path ""
					(reference "U29")
					(unit 1)
				)
			)
		)
	)
	(symbol
		(lib_id "antmicroCapacitors0603:C_22u_16V_0603")
		(at 344.17 146.05 90)
		(unit 1)
		(exclude_from_sim no)
		(in_bom yes)
		(on_board yes)
		(dnp no)
		(fields_autoplaced yes)
		(property "Reference" "C6"
			(at 346.71 140.9635 90)
			(effects
				(font
					(size 1.27 1.27)
					(thickness 0.15)
				)
				(justify right)
			)
		)
		(property "Value" "C_22u_16V_0603"
			(at 354.33 125.73 0)
			(effects
				(font
					(size 1.27 1.27)
					(thickness 0.15)
				)
				(justify left bottom)
				(hide yes)
			)
		)
		(property "Footprint" "antmicro-footprints:C_0603_1608Metric"
			(at 356.87 125.73 0)
			(effects
				(font
					(size 1.27 1.27)
					(thickness 0.15)
				)
				(justify left bottom)
				(hide yes)
			)
		)
		(property "Datasheet" "https://product.samsungsem.com/mlcc/CL10A226MO7JZN.do"
			(at 359.41 125.73 0)
			(effects
				(font
					(size 1.27 1.27)
					(thickness 0.15)
				)
				(justify left bottom)
				(hide yes)
			)
		)
		(property "Description" ""
			(at 344.17 146.05 0)
			(effects
				(font
					(size 1.27 1.27)
				)
				(hide yes)
			)
		)
		(property "MPN" "CL10A226MO7JZNC"
			(at 361.95 125.73 0)
			(effects
				(font
					(size 1.27 1.27)
					(thickness 0.15)
				)
				(justify left bottom)
				(hide yes)
			)
		)
		(property "Manufacturer" "Samsung Electro-Mechanics"
			(at 364.49 125.73 0)
			(effects
				(font
					(size 1.27 1.27)
					(thickness 0.15)
				)
				(justify left bottom)
				(hide yes)
			)
		)
		(property "License" "Apache-2.0"
			(at 367.03 125.73 0)
			(effects
				(font
					(size 1.27 1.27)
					(thickness 0.15)
				)
				(justify left bottom)
				(hide yes)
			)
		)
		(property "Author" "Antmicro"
			(at 369.57 125.73 0)
			(effects
				(font
					(size 1.27 1.27)
					(thickness 0.15)
				)
				(justify left bottom)
				(hide yes)
			)
		)
		(property "Val" "22u"
			(at 346.71 143.5035 90)
			(effects
				(font
					(size 1.27 1.27)
					(thickness 0.15)
				)
				(justify right)
			)
		)
		(property "Voltage" "16V"
			(at 346.71 146.0435 90)
			(effects
				(font
					(size 1.27 1.27)
				)
				(justify right)
				(hide yes)
			)
		)
		(property "Dielectric" ""
			(at 374.65 125.73 0)
			(effects
				(font
					(size 1.27 1.27)
				)
				(justify left bottom)
				(hide yes)
			)
		)
		(property "Public" "False"
			(at 377.19 125.73 0)
			(effects
				(font
					(size 1.27 1.27)
				)
				(justify left bottom)
				(hide yes)
			)
		)
		(pin "2"
		)
		(pin "1"
		)
		(instances
			(project "com-express-7-baseboard"
				(path ""
					(reference "C6")
					(unit 1)
				)
			)
		)
	)
	(symbol
		(lib_id "antmicropower:+1V0")
		(at 76.2 67.31 0)
		(unit 1)
		(exclude_from_sim no)
		(in_bom yes)
		(on_board yes)
		(dnp no)
		(property "Reference" "#PWR0192"
			(at 76.2 71.12 0)
			(effects
				(font
					(size 1.27 1.27)
				)
				(hide yes)
			)
		)
		(property "Value" "+1V0"
			(at 76.2 63.5 0)
			(effects
				(font
					(size 1.27 1.27)
				)
			)
		)
		(property "Footprint" ""
			(at 76.2 67.31 0)
			(effects
				(font
					(size 1.27 1.27)
				)
				(hide yes)
			)
		)
		(property "Datasheet" ""
			(at 76.2 67.31 0)
			(effects
				(font
					(size 1.27 1.27)
				)
				(hide yes)
			)
		)
		(property "Description" ""
			(at 76.2 67.31 0)
			(effects
				(font
					(size 1.27 1.27)
				)
				(hide yes)
			)
		)
		(pin "1"
		)
		(instances
			(project "com-express-7-baseboard"
				(path ""
					(reference "#PWR0192")
					(unit 1)
				)
			)
		)
	)
	(symbol
		(lib_id "antmicropower:+3V3")
		(at 148.59 71.12 0)
		(unit 1)
		(exclude_from_sim no)
		(in_bom yes)
		(on_board yes)
		(dnp no)
		(property "Reference" "#PWR0198"
			(at 163.83 71.12 0)
			(effects
				(font
					(size 1.27 1.27)
					(thickness 0.15)
				)
				(justify left bottom)
				(hide yes)
			)
		)
		(property "Value" "+3V3"
			(at 148.59 67.31 0)
			(effects
				(font
					(size 1.27 1.27)
					(thickness 0.15)
				)
			)
		)
		(property "Footprint" ""
			(at 163.83 78.74 0)
			(effects
				(font
					(size 1.27 1.27)
					(thickness 0.15)
				)
				(justify left bottom)
				(hide yes)
			)
		)
		(property "Datasheet" ""
			(at 163.83 81.28 0)
			(effects
				(font
					(size 1.27 1.27)
					(thickness 0.15)
				)
				(justify left bottom)
				(hide yes)
			)
		)
		(property "Description" ""
			(at 148.59 71.12 0)
			(effects
				(font
					(size 1.27 1.27)
				)
				(hide yes)
			)
		)
		(property "Author" "Antmicro"
			(at 163.83 73.66 0)
			(effects
				(font
					(size 1.27 1.27)
					(thickness 0.15)
				)
				(justify left bottom)
				(hide yes)
			)
		)
		(property "License" "Apache-2.0"
			(at 163.83 76.2 0)
			(effects
				(font
					(size 1.27 1.27)
					(thickness 0.15)
				)
				(justify left bottom)
				(hide yes)
			)
		)
		(pin "1"
		)
		(instances
			(project "com-express-7-baseboard"
				(path ""
					(reference "#PWR0198")
					(unit 1)
				)
			)
		)
	)
	(symbol
		(lib_id "antmicropower:+3V3")
		(at 50.8 29.21 0)
		(unit 1)
		(exclude_from_sim no)
		(in_bom yes)
		(on_board yes)
		(dnp no)
		(property "Reference" "#PWR0184"
			(at 66.04 29.21 0)
			(effects
				(font
					(size 1.27 1.27)
					(thickness 0.15)
				)
				(justify left bottom)
				(hide yes)
			)
		)
		(property "Value" "+3V3"
			(at 50.8 25.4 0)
			(effects
				(font
					(size 1.27 1.27)
					(thickness 0.15)
				)
			)
		)
		(property "Footprint" ""
			(at 66.04 36.83 0)
			(effects
				(font
					(size 1.27 1.27)
					(thickness 0.15)
				)
				(justify left bottom)
				(hide yes)
			)
		)
		(property "Datasheet" ""
			(at 66.04 39.37 0)
			(effects
				(font
					(size 1.27 1.27)
					(thickness 0.15)
				)
				(justify left bottom)
				(hide yes)
			)
		)
		(property "Description" ""
			(at 50.8 29.21 0)
			(effects
				(font
					(size 1.27 1.27)
				)
				(hide yes)
			)
		)
		(property "Author" "Antmicro"
			(at 66.04 31.75 0)
			(effects
				(font
					(size 1.27 1.27)
					(thickness 0.15)
				)
				(justify left bottom)
				(hide yes)
			)
		)
		(property "License" "Apache-2.0"
			(at 66.04 34.29 0)
			(effects
				(font
					(size 1.27 1.27)
					(thickness 0.15)
				)
				(justify left bottom)
				(hide yes)
			)
		)
		(pin "1"
		)
		(instances
			(project "com-express-7-baseboard"
				(path ""
					(reference "#PWR0184")
					(unit 1)
				)
			)
		)
	)
	(symbol
		(lib_id "antmicropower:+5V")
		(at 66.04 67.31 0)
		(unit 1)
		(exclude_from_sim no)
		(in_bom yes)
		(on_board yes)
		(dnp no)
		(property "Reference" "#PWR0189"
			(at 81.28 69.85 0)
			(effects
				(font
					(size 1.27 1.27)
					(thickness 0.15)
				)
				(justify left bottom)
				(hide yes)
			)
		)
		(property "Value" "+5V"
			(at 66.04 63.5 0)
			(effects
				(font
					(size 1.27 1.27)
					(thickness 0.15)
				)
			)
		)
		(property "Footprint" ""
			(at 81.28 74.93 0)
			(effects
				(font
					(size 1.27 1.27)
					(thickness 0.15)
				)
				(justify left bottom)
				(hide yes)
			)
		)
		(property "Datasheet" ""
			(at 81.28 77.47 0)
			(effects
				(font
					(size 1.27 1.27)
					(thickness 0.15)
				)
				(justify left bottom)
				(hide yes)
			)
		)
		(property "Description" ""
			(at 66.04 67.31 0)
			(effects
				(font
					(size 1.27 1.27)
				)
				(hide yes)
			)
		)
		(property "Author" "Antmicro"
			(at 81.28 74.93 0)
			(effects
				(font
					(size 1.27 1.27)
					(thickness 0.15)
				)
				(justify left bottom)
				(hide yes)
			)
		)
		(property "License" "Apache-2.0"
			(at 81.28 77.47 0)
			(effects
				(font
					(size 1.27 1.27)
					(thickness 0.15)
				)
				(justify left bottom)
				(hide yes)
			)
		)
		(pin "1"
		)
		(instances
			(project "com-express-7-baseboard"
				(path ""
					(reference "#PWR0189")
					(unit 1)
				)
			)
		)
	)
	(symbol
		(lib_id "antmicropower:+5V")
		(at 55.88 187.96 0)
		(unit 1)
		(exclude_from_sim no)
		(in_bom yes)
		(on_board yes)
		(dnp no)
		(property "Reference" "#PWR0185"
			(at 71.12 190.5 0)
			(effects
				(font
					(size 1.27 1.27)
					(thickness 0.15)
				)
				(justify left bottom)
				(hide yes)
			)
		)
		(property "Value" "+5V"
			(at 55.88 184.15 0)
			(effects
				(font
					(size 1.27 1.27)
					(thickness 0.15)
				)
			)
		)
		(property "Footprint" ""
			(at 71.12 195.58 0)
			(effects
				(font
					(size 1.27 1.27)
					(thickness 0.15)
				)
				(justify left bottom)
				(hide yes)
			)
		)
		(property "Datasheet" ""
			(at 71.12 198.12 0)
			(effects
				(font
					(size 1.27 1.27)
					(thickness 0.15)
				)
				(justify left bottom)
				(hide yes)
			)
		)
		(property "Description" ""
			(at 55.88 187.96 0)
			(effects
				(font
					(size 1.27 1.27)
				)
				(hide yes)
			)
		)
		(property "Author" "Antmicro"
			(at 71.12 195.58 0)
			(effects
				(font
					(size 1.27 1.27)
					(thickness 0.15)
				)
				(justify left bottom)
				(hide yes)
			)
		)
		(property "License" "Apache-2.0"
			(at 71.12 198.12 0)
			(effects
				(font
					(size 1.27 1.27)
					(thickness 0.15)
				)
				(justify left bottom)
				(hide yes)
			)
		)
		(pin "1"
		)
		(instances
			(project "com-express-7-baseboard"
				(path ""
					(reference "#PWR0185")
					(unit 1)
				)
			)
		)
	)
	(symbol
		(lib_id "antmicropower:+3V3")
		(at 307.34 144.78 0)
		(unit 1)
		(exclude_from_sim no)
		(in_bom yes)
		(on_board yes)
		(dnp no)
		(property "Reference" "#PWR0209"
			(at 322.58 144.78 0)
			(effects
				(font
					(size 1.27 1.27)
					(thickness 0.15)
				)
				(justify left bottom)
				(hide yes)
			)
		)
		(property "Value" "+3V3"
			(at 307.34 140.97 0)
			(effects
				(font
					(size 1.27 1.27)
					(thickness 0.15)
				)
			)
		)
		(property "Footprint" ""
			(at 322.58 152.4 0)
			(effects
				(font
					(size 1.27 1.27)
					(thickness 0.15)
				)
				(justify left bottom)
				(hide yes)
			)
		)
		(property "Datasheet" ""
			(at 322.58 154.94 0)
			(effects
				(font
					(size 1.27 1.27)
					(thickness 0.15)
				)
				(justify left bottom)
				(hide yes)
			)
		)
		(property "Description" ""
			(at 307.34 144.78 0)
			(effects
				(font
					(size 1.27 1.27)
				)
				(hide yes)
			)
		)
		(property "Author" "Antmicro"
			(at 322.58 147.32 0)
			(effects
				(font
					(size 1.27 1.27)
					(thickness 0.15)
				)
				(justify left bottom)
				(hide yes)
			)
		)
		(property "License" "Apache-2.0"
			(at 322.58 149.86 0)
			(effects
				(font
					(size 1.27 1.27)
					(thickness 0.15)
				)
				(justify left bottom)
				(hide yes)
			)
		)
		(pin "1"
		)
		(instances
			(project "com-express-7-baseboard"
				(path ""
					(reference "#PWR0209")
					(unit 1)
				)
			)
		)
	)
	(symbol
		(lib_id "antmicroWire2BoardConnectors:Molex_KK_1x4_0470531000")
		(at 351.79 152.4 0)
		(unit 1)
		(exclude_from_sim no)
		(in_bom yes)
		(on_board yes)
		(dnp no)
		(property "Reference" "J10"
			(at 358.14 154.94 0)
			(effects
				(font
					(size 1.27 1.27)
					(thickness 0.15)
				)
				(justify left)
			)
		)
		(property "Value" "Molex_KK_1x4_0470531000"
			(at 372.11 162.56 0)
			(effects
				(font
					(size 1.27 1.27)
					(thickness 0.15)
				)
				(justify left bottom)
				(hide yes)
			)
		)
		(property "Footprint" "antmicro-footprints:Conn_Molex_KK_1x4_0470531000"
			(at 372.11 165.1 0)
			(effects
				(font
					(size 1.27 1.27)
					(thickness 0.15)
				)
				(justify left bottom)
				(hide yes)
			)
		)
		(property "Datasheet" "https://tools.molex.com/pdm_docs/sd/470531000_sd.pdf"
			(at 372.11 167.64 0)
			(effects
				(font
					(size 1.27 1.27)
					(thickness 0.15)
				)
				(justify left bottom)
				(hide yes)
			)
		)
		(property "Description" ""
			(at 351.79 152.4 0)
			(effects
				(font
					(size 1.27 1.27)
				)
				(hide yes)
			)
		)
		(property "MPN" "0470531000"
			(at 358.14 157.48 0)
			(effects
				(font
					(size 1.27 1.27)
					(thickness 0.15)
				)
				(justify left)
			)
		)
		(property "Manufacturer" "Molex"
			(at 372.11 170.18 0)
			(effects
				(font
					(size 1.27 1.27)
					(thickness 0.15)
				)
				(justify left bottom)
				(hide yes)
			)
		)
		(property "Author" "Antmicro"
			(at 372.11 172.72 0)
			(effects
				(font
					(size 1.27 1.27)
					(thickness 0.15)
				)
				(justify left bottom)
				(hide yes)
			)
		)
		(property "License" "Apache-2.0"
			(at 372.11 175.26 0)
			(effects
				(font
					(size 1.27 1.27)
					(thickness 0.15)
				)
				(justify left bottom)
				(hide yes)
			)
		)
		(pin "4"
		)
		(pin "3"
		)
		(pin "2"
		)
		(pin "1"
		)
		(instances
			(project "com-express-7-baseboard"
				(path ""
					(reference "J10")
					(unit 1)
				)
			)
		)
	)
	(symbol
		(lib_id "antmicropower:+12V")
		(at 306.07 68.58 0)
		(unit 1)
		(exclude_from_sim no)
		(in_bom yes)
		(on_board yes)
		(dnp no)
		(fields_autoplaced yes)
		(property "Reference" "#PWR0206"
			(at 306.07 72.39 0)
			(effects
				(font
					(size 1.27 1.27)
				)
				(hide yes)
			)
		)
		(property "Value" "+12V"
			(at 306.07 63.5 0)
			(effects
				(font
					(size 1.27 1.27)
				)
			)
		)
		(property "Footprint" ""
			(at 306.07 68.58 0)
			(effects
				(font
					(size 1.27 1.27)
				)
				(hide yes)
			)
		)
		(property "Datasheet" ""
			(at 306.07 68.58 0)
			(effects
				(font
					(size 1.27 1.27)
				)
				(hide yes)
			)
		)
		(property "Description" ""
			(at 306.07 68.58 0)
			(effects
				(font
					(size 1.27 1.27)
				)
				(hide yes)
			)
		)
		(pin "1"
		)
		(instances
			(project "com-express-7-baseboard"
				(path ""
					(reference "#PWR0206")
					(unit 1)
				)
			)
		)
	)
	(symbol
		(lib_id "antmicropower:GND")
		(at 271.78 171.45 0)
		(mirror y)
		(unit 1)
		(exclude_from_sim no)
		(in_bom yes)
		(on_board yes)
		(dnp no)
		(property "Reference" "#PWR0203"
			(at 262.89 173.99 0)
			(effects
				(font
					(size 1.27 1.27)
					(thickness 0.15)
				)
				(justify left bottom)
				(hide yes)
			)
		)
		(property "Value" "GND"
			(at 271.78 175.26 0)
			(effects
				(font
					(size 1.27 1.27)
					(thickness 0.15)
				)
			)
		)
		(property "Footprint" ""
			(at 262.89 179.07 0)
			(effects
				(font
					(size 1.27 1.27)
					(thickness 0.15)
				)
				(justify left bottom)
				(hide yes)
			)
		)
		(property "Datasheet" ""
			(at 262.89 184.15 0)
			(effects
				(font
					(size 1.27 1.27)
					(thickness 0.15)
				)
				(justify left bottom)
				(hide yes)
			)
		)
		(property "Description" ""
			(at 271.78 171.45 0)
			(effects
				(font
					(size 1.27 1.27)
				)
				(hide yes)
			)
		)
		(property "Author" "Antmicro"
			(at 262.89 179.07 0)
			(effects
				(font
					(size 1.27 1.27)
					(thickness 0.15)
				)
				(justify left bottom)
				(hide yes)
			)
		)
		(property "License" "Apache-2.0"
			(at 262.89 181.61 0)
			(effects
				(font
					(size 1.27 1.27)
					(thickness 0.15)
				)
				(justify left bottom)
				(hide yes)
			)
		)
		(pin "1"
		)
		(instances
			(project "com-express-7-baseboard"
				(path ""
					(reference "#PWR0203")
					(unit 1)
				)
			)
		)
	)
	(symbol
		(lib_id "antmicroInterfaceAnalogSwitchesMultiplexersDemultiplexers:74LVC1G157-Q100H_SOT457")
		(at 278.13 120.65 0)
		(unit 1)
		(exclude_from_sim no)
		(in_bom yes)
		(on_board yes)
		(dnp no)
		(fields_autoplaced yes)
		(property "Reference" "U25"
			(at 287.02 114.3 0)
			(effects
				(font
					(size 1.27 1.27)
					(thickness 0.15)
				)
			)
		)
		(property "Value" "74LVC1G157-Q100H_SOT457"
			(at 306.07 128.27 0)
			(effects
				(font
					(size 1.27 1.27)
					(thickness 0.15)
				)
				(justify left bottom)
				(hide yes)
			)
		)
		(property "Footprint" "antmicro-footprints:SC-74-6_1.5x2.9mm_P0.95mm"
			(at 306.07 130.81 0)
			(effects
				(font
					(size 1.27 1.27)
					(thickness 0.15)
				)
				(justify left bottom)
				(hide yes)
			)
		)
		(property "Datasheet" "https://www.mouser.com/datasheet/2/916/74LVC1G157_Q100-1578792.pdf"
			(at 306.07 133.35 0)
			(effects
				(font
					(size 1.27 1.27)
					(thickness 0.15)
				)
				(justify left bottom)
				(hide yes)
			)
		)
		(property "Description" ""
			(at 278.13 120.65 0)
			(effects
				(font
					(size 1.27 1.27)
				)
				(hide yes)
			)
		)
		(property "MPN" "74LVC1G157-Q100H"
			(at 287.02 116.84 0)
			(effects
				(font
					(size 1.27 1.27)
					(thickness 0.15)
				)
			)
		)
		(property "Manufacturer" "Nexperia"
			(at 306.07 138.43 0)
			(effects
				(font
					(size 1.27 1.27)
					(thickness 0.15)
				)
				(justify left bottom)
				(hide yes)
			)
		)
		(property "Author" "Antmicro"
			(at 306.07 140.97 0)
			(effects
				(font
					(size 1.27 1.27)
					(thickness 0.15)
				)
				(justify left bottom)
				(hide yes)
			)
		)
		(property "License" "Apache-2.0"
			(at 306.07 143.51 0)
			(effects
				(font
					(size 1.27 1.27)
					(thickness 0.15)
				)
				(justify left bottom)
				(hide yes)
			)
		)
		(pin "4"
		)
		(pin "3"
		)
		(pin "2"
		)
		(pin "6"
		)
		(pin "1"
		)
		(pin "5"
		)
		(instances
			(project "com-express-7-baseboard"
				(path ""
					(reference "U25")
					(unit 1)
				)
			)
		)
	)
	(symbol
		(lib_id "antmicropower:GND")
		(at 86.36 57.15 0)
		(unit 1)
		(exclude_from_sim no)
		(in_bom yes)
		(on_board yes)
		(dnp no)
		(property "Reference" "#PWR0193"
			(at 95.25 59.69 0)
			(effects
				(font
					(size 1.27 1.27)
					(thickness 0.15)
				)
				(justify left bottom)
				(hide yes)
			)
		)
		(property "Value" "GND"
			(at 86.36 60.96 0)
			(effects
				(font
					(size 1.27 1.27)
					(thickness 0.15)
				)
			)
		)
		(property "Footprint" ""
			(at 95.25 64.77 0)
			(effects
				(font
					(size 1.27 1.27)
					(thickness 0.15)
				)
				(justify left bottom)
				(hide yes)
			)
		)
		(property "Datasheet" ""
			(at 95.25 69.85 0)
			(effects
				(font
					(size 1.27 1.27)
					(thickness 0.15)
				)
				(justify left bottom)
				(hide yes)
			)
		)
		(property "Description" ""
			(at 86.36 57.15 0)
			(effects
				(font
					(size 1.27 1.27)
				)
				(hide yes)
			)
		)
		(property "Author" "Antmicro"
			(at 95.25 64.77 0)
			(effects
				(font
					(size 1.27 1.27)
					(thickness 0.15)
				)
				(justify left bottom)
				(hide yes)
			)
		)
		(property "License" "Apache-2.0"
			(at 95.25 67.31 0)
			(effects
				(font
					(size 1.27 1.27)
					(thickness 0.15)
				)
				(justify left bottom)
				(hide yes)
			)
		)
		(pin "1"
		)
		(instances
			(project "com-express-7-baseboard"
				(path ""
					(reference "#PWR0193")
					(unit 1)
				)
			)
		)
	)
	(symbol
		(lib_id "antmicroResistors0402:R_0R_0402")
		(at 71.12 25.4 0)
		(unit 1)
		(exclude_from_sim no)
		(in_bom yes)
		(on_board yes)
		(dnp yes)
		(property "Reference" "R147"
			(at 68.58 24.13 0)
			(effects
				(font
					(size 1.27 1.27)
					(thickness 0.15)
				)
			)
		)
		(property "Value" "R_0R_0402"
			(at 91.44 38.1 0)
			(effects
				(font
					(size 1.27 1.27)
					(thickness 0.15)
				)
				(justify left bottom)
				(hide yes)
			)
		)
		(property "Footprint" "antmicro-footprints:R_0402_1005Metric"
			(at 91.44 40.64 0)
			(effects
				(font
					(size 1.27 1.27)
					(thickness 0.15)
				)
				(justify left bottom)
				(hide yes)
			)
		)
		(property "Datasheet" "https://industrial.panasonic.com/cdbs/www-data/pdf/RDA0000/AOA0000C301.pdf"
			(at 91.44 43.18 0)
			(effects
				(font
					(size 1.27 1.27)
					(thickness 0.15)
				)
				(justify left bottom)
				(hide yes)
			)
		)
		(property "Description" ""
			(at 71.12 25.4 0)
			(effects
				(font
					(size 1.27 1.27)
				)
				(hide yes)
			)
		)
		(property "MPN" "ERJ2GE0R00X"
			(at 91.44 45.72 0)
			(effects
				(font
					(size 1.27 1.27)
					(thickness 0.15)
				)
				(justify left bottom)
				(hide yes)
			)
		)
		(property "Manufacturer" "Panasonic"
			(at 91.44 48.26 0)
			(effects
				(font
					(size 1.27 1.27)
					(thickness 0.15)
				)
				(justify left bottom)
				(hide yes)
			)
		)
		(property "License" "Apache-2.0"
			(at 91.44 50.8 0)
			(effects
				(font
					(size 1.27 1.27)
					(thickness 0.15)
				)
				(justify left bottom)
				(hide yes)
			)
		)
		(property "Author" "Antmicro"
			(at 91.44 53.34 0)
			(effects
				(font
					(size 1.27 1.27)
					(thickness 0.15)
				)
				(justify left bottom)
				(hide yes)
			)
		)
		(property "Val" "0R"
			(at 78.74 24.13 0)
			(effects
				(font
					(size 1.27 1.27)
					(thickness 0.15)
				)
			)
		)
		(property "Tolerance" "~"
			(at 91.44 35.56 0)
			(effects
				(font
					(size 1.27 1.27)
				)
				(justify left bottom)
				(hide yes)
			)
		)
		(property "Current" "1A"
			(at 91.44 55.88 0)
			(effects
				(font
					(size 1.27 1.27)
					(thickness 0.15)
				)
				(justify left bottom)
				(hide yes)
			)
		)
		(property "Public" "False"
			(at 91.44 55.88 0)
			(effects
				(font
					(size 1.27 1.27)
				)
				(justify left bottom)
				(hide yes)
			)
		)
		(pin "2"
		)
		(pin "1"
		)
		(instances
			(project "com-express-7-baseboard"
				(path ""
					(reference "R147")
					(unit 1)
				)
			)
		)
	)
	(symbol
		(lib_id "antmicroMechanicalParts:Lightpipe_Bivar_SLP3-300-250-F")
		(at 29.21 265.43 0)
		(unit 1)
		(exclude_from_sim no)
		(in_bom yes)
		(on_board yes)
		(dnp no)
		(fields_autoplaced yes)
		(property "Reference" "H5"
			(at 35.56 263.8617 0)
			(effects
				(font
					(size 1.27 1.27)
					(thickness 0.15)
				)
				(justify left)
			)
		)
		(property "Value" "Lightpipe_Bivar_SLP3-300-250-F"
			(at 40.97 272.745 0)
			(effects
				(font
					(size 1.27 1.27)
					(thickness 0.15)
				)
				(justify left bottom)
				(hide yes)
			)
		)
		(property "Footprint" "antmicro-footprints:Mech_Lightpipe_Bivar_SLP3-300-250-F"
			(at 40.97 275.285 0)
			(effects
				(font
					(size 1.27 1.27)
					(thickness 0.15)
				)
				(justify left bottom)
				(hide yes)
			)
		)
		(property "Datasheet" "https://www.bivar.com/parts_content/Datasheets/SLP3-XXX-XXX-X.pdf"
			(at 40.97 277.825 0)
			(effects
				(font
					(size 1.27 1.27)
					(thickness 0.15)
				)
				(justify left bottom)
				(hide yes)
			)
		)
		(property "Description" ""
			(at 29.21 265.43 0)
			(effects
				(font
					(size 1.27 1.27)
				)
				(hide yes)
			)
		)
		(property "Manufacturer" "BIVAR"
			(at 40.97 280.365 0)
			(effects
				(font
					(size 1.27 1.27)
					(thickness 0.15)
				)
				(justify left bottom)
				(hide yes)
			)
		)
		(property "MPN" "SLP3-150-300-F"
			(at 35.56 266.4017 0)
			(effects
				(font
					(size 1.27 1.27)
					(thickness 0.15)
				)
				(justify left)
			)
		)
		(property "Author" "Antmicro"
			(at 40.97 282.905 0)
			(effects
				(font
					(size 1.27 1.27)
					(thickness 0.15)
				)
				(justify left bottom)
				(hide yes)
			)
		)
		(property "License" "Apache-2.0"
			(at 40.97 285.445 0)
			(effects
				(font
					(size 1.27 1.27)
					(thickness 0.15)
				)
				(justify left bottom)
				(hide yes)
			)
		)
		(instances
			(project "com-express-7-baseboard"
				(path ""
					(reference "H5")
					(unit 1)
				)
			)
		)
	)
	(symbol
		(lib_name "R_10k_0402_1")
		(lib_id "antmicroResistors0402:R_10k_0402")
		(at 59.69 217.17 90)
		(unit 1)
		(exclude_from_sim no)
		(in_bom yes)
		(on_board yes)
		(dnp no)
		(property "Reference" "R142"
			(at 58.42 222.25 0)
			(effects
				(font
					(size 1.27 1.27)
					(thickness 0.15)
				)
				(justify left)
			)
		)
		(property "Value" "R_10k_0402"
			(at 72.39 196.85 0)
			(effects
				(font
					(size 1.27 1.27)
					(thickness 0.15)
				)
				(justify left bottom)
				(hide yes)
			)
		)
		(property "Footprint" "antmicro-footprints:R_0402_1005Metric"
			(at 74.93 196.85 0)
			(effects
				(font
					(size 1.27 1.27)
					(thickness 0.15)
				)
				(justify left bottom)
				(hide yes)
			)
		)
		(property "Datasheet" "https://www.bourns.com/docs/product-datasheets/cr.pdf"
			(at 77.47 196.85 0)
			(effects
				(font
					(size 1.27 1.27)
					(thickness 0.15)
				)
				(justify left bottom)
				(hide yes)
			)
		)
		(property "Description" "SMD Chip Resistor, 10 kohm, ± 1%, 62.5 mW, 0402 [1005 Metric], Thick Film, General Purpose"
			(at 59.69 217.17 0)
			(effects
				(font
					(size 1.27 1.27)
				)
				(hide yes)
			)
		)
		(property "MPN" "CR0402-FX-1002GLF"
			(at 80.01 196.85 0)
			(effects
				(font
					(size 1.27 1.27)
					(thickness 0.15)
				)
				(justify left bottom)
				(hide yes)
			)
		)
		(property "Manufacturer" "Bourns"
			(at 82.55 196.85 0)
			(effects
				(font
					(size 1.27 1.27)
					(thickness 0.15)
				)
				(justify left bottom)
				(hide yes)
			)
		)
		(property "License" "Apache-2.0"
			(at 85.09 196.85 0)
			(effects
				(font
					(size 1.27 1.27)
					(thickness 0.15)
				)
				(justify left bottom)
				(hide yes)
			)
		)
		(property "Author" "Antmicro"
			(at 87.63 196.85 0)
			(effects
				(font
					(size 1.27 1.27)
					(thickness 0.15)
				)
				(justify left bottom)
				(hide yes)
			)
		)
		(property "Val" "10k"
			(at 58.42 212.09 0)
			(effects
				(font
					(size 1.27 1.27)
					(thickness 0.15)
				)
				(justify left)
			)
		)
		(property "Tolerance" "1%"
			(at 69.85 196.85 0)
			(effects
				(font
					(size 1.27 1.27)
				)
				(justify left bottom)
				(hide yes)
			)
		)
		(pin "2"
		)
		(pin "1"
		)
		(instances
			(project "com-express-7-baseboard"
				(path ""
					(reference "R142")
					(unit 1)
				)
			)
		)
	)
	(symbol
		(lib_id "antmicropower:GND")
		(at 307.34 107.95 0)
		(mirror y)
		(unit 1)
		(exclude_from_sim no)
		(in_bom yes)
		(on_board yes)
		(dnp no)
		(property "Reference" "#PWR0208"
			(at 298.45 110.49 0)
			(effects
				(font
					(size 1.27 1.27)
					(thickness 0.15)
				)
				(justify left bottom)
				(hide yes)
			)
		)
		(property "Value" "GND"
			(at 307.34 111.76 0)
			(effects
				(font
					(size 1.27 1.27)
					(thickness 0.15)
				)
			)
		)
		(property "Footprint" ""
			(at 298.45 115.57 0)
			(effects
				(font
					(size 1.27 1.27)
					(thickness 0.15)
				)
				(justify left bottom)
				(hide yes)
			)
		)
		(property "Datasheet" ""
			(at 298.45 120.65 0)
			(effects
				(font
					(size 1.27 1.27)
					(thickness 0.15)
				)
				(justify left bottom)
				(hide yes)
			)
		)
		(property "Description" ""
			(at 307.34 107.95 0)
			(effects
				(font
					(size 1.27 1.27)
				)
				(hide yes)
			)
		)
		(property "Author" "Antmicro"
			(at 298.45 115.57 0)
			(effects
				(font
					(size 1.27 1.27)
					(thickness 0.15)
				)
				(justify left bottom)
				(hide yes)
			)
		)
		(property "License" "Apache-2.0"
			(at 298.45 118.11 0)
			(effects
				(font
					(size 1.27 1.27)
					(thickness 0.15)
				)
				(justify left bottom)
				(hide yes)
			)
		)
		(pin "1"
		)
		(instances
			(project "com-express-7-baseboard"
				(path ""
					(reference "#PWR0208")
					(unit 1)
				)
			)
		)
	)
	(symbol
		(lib_id "antmicropower:GND")
		(at 271.78 115.57 0)
		(mirror y)
		(unit 1)
		(exclude_from_sim no)
		(in_bom yes)
		(on_board yes)
		(dnp no)
		(property "Reference" "#PWR0201"
			(at 262.89 118.11 0)
			(effects
				(font
					(size 1.27 1.27)
					(thickness 0.15)
				)
				(justify left bottom)
				(hide yes)
			)
		)
		(property "Value" "GND"
			(at 271.78 119.38 0)
			(effects
				(font
					(size 1.27 1.27)
					(thickness 0.15)
				)
			)
		)
		(property "Footprint" ""
			(at 262.89 123.19 0)
			(effects
				(font
					(size 1.27 1.27)
					(thickness 0.15)
				)
				(justify left bottom)
				(hide yes)
			)
		)
		(property "Datasheet" ""
			(at 262.89 128.27 0)
			(effects
				(font
					(size 1.27 1.27)
					(thickness 0.15)
				)
				(justify left bottom)
				(hide yes)
			)
		)
		(property "Description" ""
			(at 271.78 115.57 0)
			(effects
				(font
					(size 1.27 1.27)
				)
				(hide yes)
			)
		)
		(property "Author" "Antmicro"
			(at 262.89 123.19 0)
			(effects
				(font
					(size 1.27 1.27)
					(thickness 0.15)
				)
				(justify left bottom)
				(hide yes)
			)
		)
		(property "License" "Apache-2.0"
			(at 262.89 125.73 0)
			(effects
				(font
					(size 1.27 1.27)
					(thickness 0.15)
				)
				(justify left bottom)
				(hide yes)
			)
		)
		(pin "1"
		)
		(instances
			(project "com-express-7-baseboard"
				(path ""
					(reference "#PWR0201")
					(unit 1)
				)
			)
		)
	)
	(symbol
		(lib_id "antmicroLEDIndicationDiscrete:LED_RGB_PLCC4_ASMB_MTB1_0A3A2")
		(at 101.6 207.01 270)
		(mirror x)
		(unit 1)
		(exclude_from_sim no)
		(in_bom yes)
		(on_board yes)
		(dnp no)
		(fields_autoplaced yes)
		(property "Reference" "D18"
			(at 106.68 196.215 90)
			(effects
				(font
					(size 1.27 1.27)
				)
				(justify left)
			)
		)
		(property "Value" "LED_RGB_PLCC4_ASMB_MTB1_0A3A2"
			(at 91.44 173.99 0)
			(effects
				(font
					(size 1.27 1.27)
				)
				(justify left bottom)
				(hide yes)
			)
		)
		(property "Footprint" "antmicro-footprints:PLCC4_3.2x2.8mm"
			(at 88.9 173.99 0)
			(effects
				(font
					(size 1.27 1.27)
				)
				(justify left bottom)
				(hide yes)
			)
		)
		(property "Datasheet" "https://docs.broadcom.com/doc/AV02-4194EN"
			(at 86.36 173.99 0)
			(effects
				(font
					(size 1.27 1.27)
				)
				(justify left bottom)
				(hide yes)
			)
		)
		(property "Description" ""
			(at 101.6 207.01 0)
			(effects
				(font
					(size 1.27 1.27)
				)
				(hide yes)
			)
		)
		(property "MPN" "ASMB-MTB1-0A3A2"
			(at 93.98 173.99 0)
			(effects
				(font
					(size 1.27 1.27)
				)
				(justify left bottom)
				(hide yes)
			)
		)
		(property "Manufacturer" "Avago Technologies"
			(at 83.82 173.99 0)
			(effects
				(font
					(size 1.27 1.27)
				)
				(justify left bottom)
				(hide yes)
			)
		)
		(property "Color" "R, G, B"
			(at 106.68 198.755 90)
			(effects
				(font
					(size 1.27 1.27)
				)
				(justify left)
			)
		)
		(property "Author" "Antmicro"
			(at 81.28 173.99 0)
			(effects
				(font
					(size 1.27 1.27)
				)
				(justify left bottom)
				(hide yes)
			)
		)
		(property "License" "Apache-2.0"
			(at 78.74 173.99 0)
			(effects
				(font
					(size 1.27 1.27)
				)
				(justify left bottom)
				(hide yes)
			)
		)
		(pin "2"
		)
		(pin "1"
		)
		(pin "3"
		)
		(pin "4"
		)
		(instances
			(project "com-express-7-baseboard"
				(path ""
					(reference "D18")
					(unit 1)
				)
			)
		)
	)
	(symbol
		(lib_id "antmicroInterfaceAnalogSwitchesMultiplexersDemultiplexers:74LVC1G157-Q100H_SOT457")
		(at 278.13 176.53 0)
		(unit 1)
		(exclude_from_sim no)
		(in_bom yes)
		(on_board yes)
		(dnp no)
		(fields_autoplaced yes)
		(property "Reference" "U26"
			(at 287.02 170.18 0)
			(effects
				(font
					(size 1.27 1.27)
					(thickness 0.15)
				)
			)
		)
		(property "Value" "74LVC1G157-Q100H_SOT457"
			(at 306.07 184.15 0)
			(effects
				(font
					(size 1.27 1.27)
					(thickness 0.15)
				)
				(justify left bottom)
				(hide yes)
			)
		)
		(property "Footprint" "antmicro-footprints:SC-74-6_1.5x2.9mm_P0.95mm"
			(at 306.07 186.69 0)
			(effects
				(font
					(size 1.27 1.27)
					(thickness 0.15)
				)
				(justify left bottom)
				(hide yes)
			)
		)
		(property "Datasheet" "https://www.mouser.com/datasheet/2/916/74LVC1G157_Q100-1578792.pdf"
			(at 306.07 189.23 0)
			(effects
				(font
					(size 1.27 1.27)
					(thickness 0.15)
				)
				(justify left bottom)
				(hide yes)
			)
		)
		(property "Description" ""
			(at 278.13 176.53 0)
			(effects
				(font
					(size 1.27 1.27)
				)
				(hide yes)
			)
		)
		(property "MPN" "74LVC1G157-Q100H"
			(at 287.02 172.72 0)
			(effects
				(font
					(size 1.27 1.27)
					(thickness 0.15)
				)
			)
		)
		(property "Manufacturer" "Nexperia"
			(at 306.07 194.31 0)
			(effects
				(font
					(size 1.27 1.27)
					(thickness 0.15)
				)
				(justify left bottom)
				(hide yes)
			)
		)
		(property "Author" "Antmicro"
			(at 306.07 196.85 0)
			(effects
				(font
					(size 1.27 1.27)
					(thickness 0.15)
				)
				(justify left bottom)
				(hide yes)
			)
		)
		(property "License" "Apache-2.0"
			(at 306.07 199.39 0)
			(effects
				(font
					(size 1.27 1.27)
					(thickness 0.15)
				)
				(justify left bottom)
				(hide yes)
			)
		)
		(pin "4"
		)
		(pin "3"
		)
		(pin "2"
		)
		(pin "6"
		)
		(pin "1"
		)
		(pin "5"
		)
		(instances
			(project "com-express-7-baseboard"
				(path ""
					(reference "U26")
					(unit 1)
				)
			)
		)
	)
	(symbol
		(lib_id "antmicropower:GND")
		(at 95.25 115.57 0)
		(unit 1)
		(exclude_from_sim no)
		(in_bom yes)
		(on_board yes)
		(dnp no)
		(property "Reference" "#PWR0194"
			(at 104.14 118.11 0)
			(effects
				(font
					(size 1.27 1.27)
					(thickness 0.15)
				)
				(justify left bottom)
				(hide yes)
			)
		)
		(property "Value" "GND"
			(at 95.25 119.38 0)
			(effects
				(font
					(size 1.27 1.27)
					(thickness 0.15)
				)
			)
		)
		(property "Footprint" ""
			(at 104.14 123.19 0)
			(effects
				(font
					(size 1.27 1.27)
					(thickness 0.15)
				)
				(justify left bottom)
				(hide yes)
			)
		)
		(property "Datasheet" ""
			(at 104.14 128.27 0)
			(effects
				(font
					(size 1.27 1.27)
					(thickness 0.15)
				)
				(justify left bottom)
				(hide yes)
			)
		)
		(property "Description" ""
			(at 95.25 115.57 0)
			(effects
				(font
					(size 1.27 1.27)
				)
				(hide yes)
			)
		)
		(property "Author" "Antmicro"
			(at 104.14 123.19 0)
			(effects
				(font
					(size 1.27 1.27)
					(thickness 0.15)
				)
				(justify left bottom)
				(hide yes)
			)
		)
		(property "License" "Apache-2.0"
			(at 104.14 125.73 0)
			(effects
				(font
					(size 1.27 1.27)
					(thickness 0.15)
				)
				(justify left bottom)
				(hide yes)
			)
		)
		(pin "1"
		)
		(instances
			(project "com-express-7-baseboard"
				(path ""
					(reference "#PWR0194")
					(unit 1)
				)
			)
		)
	)
	(symbol
		(lib_id "antmicropower:GND")
		(at 344.17 196.85 0)
		(unit 1)
		(exclude_from_sim no)
		(in_bom yes)
		(on_board yes)
		(dnp no)
		(property "Reference" "#PWR0263"
			(at 353.06 199.39 0)
			(effects
				(font
					(size 1.27 1.27)
					(thickness 0.15)
				)
				(justify left bottom)
				(hide yes)
			)
		)
		(property "Value" "GND"
			(at 344.17 200.66 0)
			(effects
				(font
					(size 1.27 1.27)
					(thickness 0.15)
				)
			)
		)
		(property "Footprint" ""
			(at 353.06 204.47 0)
			(effects
				(font
					(size 1.27 1.27)
					(thickness 0.15)
				)
				(justify left bottom)
				(hide yes)
			)
		)
		(property "Datasheet" ""
			(at 353.06 209.55 0)
			(effects
				(font
					(size 1.27 1.27)
					(thickness 0.15)
				)
				(justify left bottom)
				(hide yes)
			)
		)
		(property "Description" ""
			(at 344.17 196.85 0)
			(effects
				(font
					(size 1.27 1.27)
				)
				(hide yes)
			)
		)
		(property "Author" "Antmicro"
			(at 353.06 204.47 0)
			(effects
				(font
					(size 1.27 1.27)
					(thickness 0.15)
				)
				(justify left bottom)
				(hide yes)
			)
		)
		(property "License" "Apache-2.0"
			(at 353.06 207.01 0)
			(effects
				(font
					(size 1.27 1.27)
					(thickness 0.15)
				)
				(justify left bottom)
				(hide yes)
			)
		)
		(pin "1"
		)
		(instances
			(project "com-express-7-baseboard"
				(path ""
					(reference "#PWR0263")
					(unit 1)
				)
			)
		)
	)
)
